G04 ================== begin FILE IDENTIFICATION RECORD ==================*
G04 Layout Name:  14545-sa.brd*
G04 Film Name:    L8*
G04 File Format:  Gerber RS274X*
G04 File Origin:  Cadence Allegro 16.5-S056*
G04 Origin Date:  Fri Aug 01 17:58:58 2014*
G04 *
G04 Layer:  VIA CLASS/BOTTOM*
G04 Layer:  PIN/BOTTOM*
G04 Layer:  ETCH/BOTTOM*
G04 Layer:  DRAWING FORMAT/LAYER_PCB_STORY*
G04 Layer:  DRAWING FORMAT/LAYER_L8*
G04 *
G04 Offset:    (0.00 0.00)*
G04 Mirror:    No*
G04 Mode:      Positive*
G04 Rotation:  0*
G04 FullContactRelief:  No*
G04 UndefLineWidth:     6.00*
G04 ================== end FILE IDENTIFICATION RECORD ====================*
%FSLAX35Y35*MOIN*%
%IR0*IPPOS*OFA0.00000B0.00000*MIA0B0*SFA1.00000B1.00000*%
%ADD16O,.103X.06*%
%ADD20R,.23X.032*%
%AMMACRO18*
4,1,8,.197,-.186,
-.197,-.186,
-.197,.186,
.197,.186,
.197,.00925,
-.059,.00925,
-.059,-.00925,
.197,-.00925,
.197,-.186,
0.0*
%
%ADD18MACRO18*%
%ADD11C,.01*%
%ADD13R,.142X.028*%
%ADD14C,.022*%
%ADD12C,.028*%
%ADD10R,.05X.05*%
%ADD17R,.001X.001*%
%ADD15C,.315*%
%ADD19R,.394X.172*%
%ADD21C,.02*%
%ADD22C,.03*%
%ADD23C,.04*%
%ADD24C,.016*%
%ADD25C,.025*%
%ADD26C,.006*%
%ADD27C,.00438*%
%ADD28C,.00375*%
%ADD29O,.12702X.08402*%
%ADD34C,.05204*%
%ADD35C,.04604*%
%ADD32C,.09704*%
%ADD30C,.11504*%
%ADD33C,.17004*%
%ADD31R,.17202X.17204*%
%ADD36C,.33904*%
G75*
%LPD*%
G75*
G36*
G01X3999Y3000D02*
X3500Y3499D01*
Y165700D01*
X5600Y167800D01*
X21798D01*
Y117887D01*
G03Y115113I2202J-1387D01*
G01Y111412D01*
X14669Y104283D01*
X14644Y104269D01*
G03X17769Y101144I1106J-2019D01*
G01X17783Y101169D01*
X26202Y109588D01*
Y113134D01*
G02X26884Y113417I400J0D01*
G01X31002Y109298D01*
X47998D01*
X51952Y113252D01*
Y187748D01*
X36998Y202702D01*
X34700D01*
Y203700D01*
X33300Y205100D01*
X29800D01*
X28300Y206600D01*
Y220300D01*
X25900Y222700D01*
X24800D01*
X21900Y225600D01*
Y249200D01*
X20300Y250800D01*
X4700D01*
X3500Y252000D01*
Y354000D01*
X3475Y354025D01*
Y358025D01*
X11500Y366050D01*
X39394D01*
X58197Y347247D01*
G02X58445Y346911I-995J-994D01*
G02X58610Y346252I-1242J-661D01*
G01Y146233D01*
G03X60096Y142647I5077J3D01*
G01X61024Y141719D01*
X61348Y141397D01*
X61720Y141024D01*
X81053Y121691D01*
G03X81353Y121405I5743J5724D01*
G01X81354Y121404D01*
G03X86671Y119360I5317J5894D01*
G01X94974D01*
G03X100334Y121581I-3J7586D01*
G01X103765Y125012D01*
G02X104833Y125689I2050J-2052D01*
G02X105815Y125860I981J-2729D01*
G01X113570D01*
X113592Y125685D01*
G03X118003Y126854I2284J288D01*
G01X117988Y126891D01*
Y129132D01*
X118003Y129169D01*
G03X113575Y130132I-2127J880D01*
G01X113569Y129940D01*
X105814D01*
G03X100882Y127898I1J-6980D01*
G01X97450Y124467D01*
G02X94970Y123440I-2479J2479D01*
G01X86672D01*
G02X84088Y124433I0J3858D01*
G02X83939Y124575I2704J2986D01*
G01X64231Y144283D01*
X63907Y144606D01*
X62981Y145532D01*
G02X62688Y146238I705J706D01*
G01Y187485D01*
G02X63407Y187728I400J1D01*
G03X66748Y186074I3341J2547D01*
G01X71048D01*
G03Y194476I0J4201D01*
G01X66748D01*
G03X63407Y192822I0J-4201D01*
G02X62688Y193065I-319J242D01*
G01Y223215D01*
G02X63428Y223426I400J0D01*
G03X64473Y222110I6272J3907D01*
G01X91024Y195559D01*
G02X98610Y177250I-18308J-18312D01*
G01Y135049D01*
X98609Y135045D01*
Y134996D01*
G02X97596Y132552I-3456J0D01*
G02X92014Y130240I-5582J5582D01*
G01X89610D01*
G02X89210Y130629I0J400D01*
G03X84595Y130747I-2311J-63D01*
G01X84295Y126931D01*
G03X88793Y126023I2304J-180D01*
G01X88839Y126160D01*
X92015D01*
G03X100482Y129667I0J11974D01*
G03X102688Y134995I-5330J5327D01*
G01Y177250D01*
G03X96586Y195377I-29974J1D01*
G02X97026Y196000I319J242D01*
G03X97999Y195848I975J3050D01*
G01X121673D01*
X139673Y177848D01*
X155999D01*
G03Y184252I0J3202D01*
G01X142325D01*
X124325Y202252D01*
X97999D01*
G03X94839Y198537I0J-3201D01*
G02X94158Y198193I-395J-65D01*
G03X93910Y198445I-21487J-20898D01*
G01X67358Y224996D01*
G02X66388Y227335I2339J2341D01*
G01Y288551D01*
G02X67126Y288765I400J0D01*
G03X68115Y287529I6074J3847D01*
G01X123028Y232616D01*
G03X128112Y230510I5084J5084D01*
G01X819160D01*
G03X825312Y233058I0J8700D01*
G01X841078Y248825D01*
G02X841863Y249150I785J-785D01*
G01X845745D01*
G03X847834Y247729I2133J890D01*
G01X851233Y247663D01*
G03X851323Y252285I45J2311D01*
G01X850924Y252293D01*
X850868Y252344D01*
G03X850692Y252494I-2291J-2510D01*
G02X850816Y252850I124J156D01*
G01X859116D01*
G02X859316Y252767I0J-283D01*
G01X870916Y241167D01*
G03X874555Y239660I3639J3639D01*
G01X875804D01*
X875843Y239512D01*
G03X880390Y240102I2235J590D01*
G01Y243878D01*
G03X875767Y243935I-2312J0D01*
G01X875762Y243740D01*
X874273D01*
G02X874001Y243852I0J385D01*
G01X862201Y255653D01*
G03X859118Y256930I-3083J-3083D01*
G01X839875D01*
G03X834651Y254766I0J-7387D01*
G01X819523Y239640D01*
G02X816263Y238290I-3259J3260D01*
G01X152503D01*
G02X152134Y238843I0J400D01*
G03X152310Y239728I-2135J885D01*
G01Y243504D01*
G03X147854Y244365I-2311J0D01*
G01X147803Y244240D01*
X140335D01*
G02X140232Y244282I0J146D01*
G01X133631Y250883D01*
G02X133449Y251085I1791J1797D01*
G02X132888Y252675I1976J1591D01*
G01Y256550D01*
G03X131369Y260220I-5190J1D01*
G01X130999Y260589D01*
X128538Y263056D01*
X128532D01*
X82069Y309520D01*
G02X81188Y311644I2123J2125D01*
G01Y366040D01*
X81399Y366250D01*
Y378650D01*
X34499Y425550D01*
Y431014D01*
X67583D01*
G02X69010Y430539I1J-2379D01*
G01X72186Y427363D01*
G02X71829Y426687I-283J-283D01*
G03X71048Y426760I-780J-4128D01*
G01X66748D01*
G03Y418358I0J-4201D01*
G01X71048D01*
G03X74160Y425381I0J4201D01*
G02X74457Y426050I296J269D01*
G01X74635D01*
X74660Y426044D01*
G03X76097Y425860I1441J5554D01*
G01X81626D01*
G03X82990Y426043I-2J5190D01*
G01X83016Y426050D01*
X84499D01*
X89248Y430800D01*
X276300D01*
X280100Y431000D01*
X284300Y432400D01*
X838200Y654400D01*
X844100D01*
X846400Y653100D01*
X847431Y653083D01*
X847443Y653082D01*
G03X847814Y653059I328J2288D01*
G01X848358Y653068D01*
X852600Y653000D01*
X852700Y653100D01*
X856483D01*
X860024Y649559D01*
X863100Y645900D01*
X865100Y645300D01*
X865846D01*
X865860Y645298D01*
G03X866636Y645244I772J5490D01*
G01X875256D01*
X877300Y643200D01*
X879800D01*
X881100Y644500D01*
Y650600D01*
X879900Y651800D01*
X877500D01*
X876300Y650600D01*
Y649800D01*
X875900Y649400D01*
X866168D01*
G02X865600Y649753I471J1391D01*
G01X854828Y660526D01*
G03X849603Y662690I-5225J-5226D01*
G01X835868D01*
G03X833658Y662351I3J-7390D01*
G01X206684Y465538D01*
X206600Y465600D01*
X205800D01*
X196100Y475300D01*
Y476587D01*
X779279Y1059765D01*
G02X781299Y1060602I2021J-2021D01*
G01X845100D01*
G03X847200Y1059181I2133J890D01*
G01X850800Y1059130D01*
G03X850865Y1063752I33J2311D01*
G01X850469Y1063758D01*
X850415Y1063804D01*
G03X849946Y1064138I-2411J-2889D01*
G02X850050Y1064510I103J172D01*
G01X867280D01*
G02X867612Y1064371I-1J-469D01*
G01X867729Y1064255D01*
G02X867748Y1064207I-50J-48D01*
G01Y1055547D01*
G03X869199Y1052045I4957J2D01*
G01X869397Y1051847D01*
G03X872749Y1050460I3350J3352D01*
G01X875000D01*
G03X875990Y1050535I-4J6625D01*
G03X880537Y1051279I2243J561D01*
G01X880268Y1054668D01*
G03X875657Y1054626I-2304J-183D01*
G02X874999Y1054540I-656J2459D01*
G01X872748D01*
G02X872281Y1054733I-1J659D01*
G01X872085Y1054930D01*
G02X871828Y1055550I619J620D01*
G01Y1064210D01*
G03X870607Y1067147I-4149J-3D01*
G01X870490Y1067262D01*
X870489Y1067263D01*
G03X867281Y1068588I-3209J-3223D01*
G01X781489D01*
G03X773436Y1065253I0J-11389D01*
G01X199383Y491198D01*
G02X198701Y491481I-282J283D01*
G01Y496048D01*
X158997Y535752D01*
X151341D01*
G02X150995Y536351I1J400D01*
G03X151253Y537973I-1995J1149D01*
G02X151393Y538206I196J41D01*
G03X151856Y542435I-643J2210D01*
G02X151819Y543113I192J351D01*
G03X149394Y542981I-1319J1887D01*
G02X149431Y542303I-192J-351D01*
G03X148939Y541836I1321J-1885D01*
G01X112772D01*
X111687Y542922D01*
X111694Y543014D01*
G03X107836Y544889I-2294J186D01*
G02X107564I-136J147D01*
G03X106186Y540906I-1564J-1689D01*
G01X106278Y540913D01*
X111112Y536080D01*
X143364D01*
G02X143647Y535397I0J-400D01*
G01X142298Y534048D01*
Y522052D01*
X146001Y518348D01*
X156501D01*
Y505451D01*
G03X156521Y505360I398J40D01*
G02X156324Y504872I-378J-131D01*
G03X156158Y504780I1178J-2321D01*
G01X156111Y504752D01*
X154887D01*
X154840Y504780D01*
G03X151549Y504273I-1341J-2230D01*
G02X150949I-300J264D01*
G03Y500827I-1950J-1723D01*
G02X151549I300J-264D01*
G03X154840Y500320I1950J1723D01*
G01X154887Y500348D01*
X156111D01*
X156158Y500320D01*
G03X156324Y500228I1344J2229D01*
G02X156521Y499740I-181J-357D01*
G03X156501Y499649I378J-131D01*
G01Y496470D01*
X142563D01*
G02X142288Y497161I0J400D01*
G03X138679Y500909I-1789J1889D01*
G02X138119I-280J286D01*
G03X134510Y497161I-1820J-1859D01*
G02X134235Y496470I-275J-291D01*
G01X126179D01*
G03X121819I-2180J-1420D01*
G01X110195D01*
G02X109796Y496897I0J400D01*
G03X105202I-2297J153D01*
G02X104803Y496470I-399J-27D01*
G01X83041D01*
X82991Y496520D01*
X81488D01*
X67020Y510989D01*
Y512439D01*
G03X65824Y516541I-1421J1811D01*
G02X65581Y517222I40J398D01*
G01X76031Y527672D01*
X76161Y527818D01*
X77960Y530011D01*
X80999Y533050D01*
X83659Y536309D01*
X83888Y536122D01*
Y536027D01*
G03Y536025I2311J-1D01*
G01Y532250D01*
G03X88504Y532074I2311J0D01*
G01X88510Y532162D01*
Y536035D01*
G03X86163Y538336I-2311J-10D01*
G02X85847Y538989I-6J400D01*
G01X156499Y625550D01*
Y625780D01*
X836717Y1455230D01*
X846483Y1464996D01*
G02X847079Y1464962I283J-283D01*
G03X848851Y1464091I1808J1440D01*
G01X852250Y1464035D01*
G03X852326Y1468657I38J2311D01*
G01X851850Y1468665D01*
X851798Y1468704D01*
G03X851170Y1469113I-3747J-5067D01*
G02X851368Y1469860I198J347D01*
G01X853607D01*
G02X856366Y1468717I0J-3902D01*
G01X867503Y1457580D01*
G03X871173Y1456060I3670J3670D01*
G01X875770D01*
X875807Y1455907D01*
G03X880365Y1456489I2247J542D01*
G01X880363Y1456573D01*
X880372Y1456581D01*
X880170Y1460124D01*
X880168Y1460123D01*
X880142Y1460314D01*
G03X875564Y1460312I-2289J-322D01*
G01X875540Y1460140D01*
X871173D01*
G02X870388Y1460465I0J1110D01*
G01X859470Y1471384D01*
G03X853299Y1473940I-6171J-6171D01*
G01X835441D01*
G03X831246Y1472202I1J-5934D01*
G01X825032Y1465987D01*
G02X824357Y1466349I-283J283D01*
G03X822551Y1464543I-2257J451D01*
G02X822913Y1463868I79J-392D01*
G01X816996Y1457951D01*
X816122Y1456873D01*
X156765Y643329D01*
X156499Y643423D01*
X156420Y643451D01*
X127497Y607216D01*
X67210Y532832D01*
X65574Y530812D01*
X64575Y529597D01*
X63265Y528120D01*
X46872Y511728D01*
X44499Y511050D01*
X37699D01*
X37099Y511650D01*
Y515150D01*
X37844Y515895D01*
X37857Y515904D01*
G03X38370Y516417I-1358J1871D01*
G01X38379Y516430D01*
X39221Y517272D01*
X39233Y517281D01*
G03X39768Y517740I-2733J3727D01*
G01X41086Y519058D01*
X41278Y519247D01*
X41286Y519253D01*
G03X41527Y519506I-878J1077D01*
G01X85655Y579277D01*
X125162Y644695D01*
G02X125872Y644645I342J-207D01*
G03X127407Y643316I2127J905D01*
G01X127409D01*
X130779Y642374D01*
G03X133705Y644424I621J2226D01*
G01X133712Y644512D01*
Y644610D01*
G03X132021Y646826I-2311J-11D01*
G01X128620Y647776D01*
G03X127810Y647854I-623J-2226D01*
G02X127435Y648459I-33J399D01*
G01X152006Y689146D01*
X156499Y696550D01*
Y696586D01*
X160082Y702520D01*
X161619Y705066D01*
X164330Y709554D01*
X175111Y727407D01*
X197803Y760826D01*
X293648Y923692D01*
X294756Y925527D01*
X815104Y1787176D01*
X817851Y1791721D01*
X855512Y1854085D01*
X857734Y1857752D01*
X858388Y1858830D01*
G02X859797Y1860627I8141J-4932D01*
G02X863498Y1862160I3702J-3702D01*
G01X864602D01*
Y1861840D01*
G03X869226Y1861839I2312J0D01*
G01Y1864200D01*
G02X869908Y1864483I400J0D01*
G01X916078Y1818313D01*
Y1798361D01*
G03X918919I1421J-1811D01*
G01Y1819489D01*
X866963Y1871446D01*
X866112D01*
X856318Y1881240D01*
G02X856336Y1881823I283J283D01*
G03X852704Y1884470I-1522J1727D01*
G01X836179D01*
G03X831819I-2180J-1420D01*
G01X816038D01*
X784420Y1916089D01*
Y1935239D01*
G03X781578I-1421J1811D01*
G01Y1914913D01*
X805956Y1890535D01*
G02X805707Y1889854I-283J-283D01*
G03X808194Y1887367I193J-2294D01*
G02X808875Y1887616I398J-34D01*
G01X811069Y1885422D01*
G02X810803Y1884740I-283J-282D01*
G03X813200Y1882343I97J-2300D01*
G02X813882Y1882609I400J-17D01*
G01X814862Y1881630D01*
X831819D01*
G03X836179I2180J1420D01*
G01X851911D01*
X864936Y1868604D01*
X865787D01*
X866041Y1868350D01*
G02X865928Y1867706I-283J-282D01*
G03X864731Y1866374I987J-2090D01*
G01X864684Y1866240D01*
X863498D01*
G03X856913Y1863513I0J-9315D01*
G03X854904Y1860951I9595J-9593D01*
G03X854892Y1860932I1168J-751D01*
G01Y1860931D01*
X854246Y1859866D01*
X852021Y1856196D01*
X814360Y1793831D01*
X811613Y1789286D01*
X343681Y1014432D01*
G02X342993Y1014842I-343J207D01*
G01X846001Y1869589D01*
X846456Y1870360D01*
X847890D01*
X847939Y1870232D01*
G03X850085Y1868745I2159J824D01*
G01X853485Y1868725D01*
G03X853512Y1873347I14J2311D01*
G01X853108Y1873350D01*
X853054Y1873392D01*
G03X849999Y1874440I-3055J-3929D01*
G01X846259D01*
G03X843038Y1872597I1J-3738D01*
G01X842800Y1872191D01*
X842423Y1871554D01*
X191225Y764989D01*
X157230Y714923D01*
G02X156499Y715148I-331J225D01*
G01Y741613D01*
G02X156988Y742003I400J0D01*
G03Y751461I1083J4729D01*
G02X156499Y751851I-89J390D01*
G01Y766050D01*
X158715Y768266D01*
G02X159398Y767992I283J-283D01*
G03X162057Y770651I2601J58D01*
G02X161783Y771334I9J400D01*
G01X197399Y806950D01*
Y807399D01*
X198499Y808499D01*
Y894679D01*
G02X199180Y894963I400J0D01*
G03X202278Y894836I1619J1637D01*
G02X202823Y894807I257J-307D01*
G03X202814Y898404I1876J1803D01*
G02X202269Y898372I-290J276D01*
G03X199180Y898237I-1470J-1772D01*
G02X198499Y898521I-281J284D01*
G01Y1179550D01*
X174999Y1203050D01*
Y1289550D01*
G02X175412Y1289949I400J-1D01*
G03X177449Y1290827I87J2601D01*
G02X178049I300J-264D01*
G03X181915Y1294311I1950J1723D01*
G02Y1294852I294J271D01*
G03X181480Y1298753I-1916J1761D01*
G02Y1299410I227J328D01*
G03X181722Y1303500I-1481J2140D01*
G02Y1304100I264J300D01*
G03X178073Y1307799I-1722J1950D01*
G02X177473Y1307808I-296J269D01*
G03X175412Y1308714I-1975J-1695D01*
G02X174999Y1309113I-13J400D01*
G01Y1386050D01*
X177499Y1388550D01*
Y1435050D01*
X119999Y1492550D01*
Y1621550D01*
X118588Y1622960D01*
Y1647522D01*
G02X120299Y1651650I5838J-1D01*
G01X151699Y1683051D01*
G03X155938Y1693287I-10239J10236D01*
G01Y1801601D01*
G03X154734Y1805575I-7158J1D01*
G01X154700Y1805626D01*
Y1807400D01*
X152100Y1810000D01*
Y1875200D01*
X150800Y1876500D01*
X124139D01*
X124116Y1876505D01*
G03X123068I-524J-2251D01*
G01X123045Y1876500D01*
X120900D01*
X119300Y1874900D01*
Y1846600D01*
X118224Y1845524D01*
X98524D01*
X98499Y1845550D01*
X35981D01*
X35760Y1845770D01*
X31410D01*
G03X27635Y1845550I-1811J-1420D01*
G01X4499D01*
X3199Y1846850D01*
Y1893060D01*
G02X3924Y1893292I400J0D01*
G03X33916Y1898137I13796J9852D01*
G02X34581Y1898302I382J-118D01*
G01X44034Y1888848D01*
X46612D01*
G03X49386I1387J2202D01*
G01X53298D01*
Y1879552D01*
X56501Y1876348D01*
X78501D01*
X78798Y1876052D01*
Y1867052D01*
X83001Y1862848D01*
X104497D01*
X108200Y1866552D01*
Y1891552D01*
X118497Y1901848D01*
X130997D01*
X138700Y1909552D01*
Y1950548D01*
X133582Y1955666D01*
G02X133865Y1956349I283J283D01*
G01X138997D01*
X140700Y1958052D01*
Y1983048D01*
X136497Y1987252D01*
X118001D01*
X114798Y1984048D01*
Y1973500D01*
X109500D01*
X109252Y1973252D01*
X99001D01*
X96501Y1970752D01*
X50001D01*
X45756Y1966506D01*
X42311Y1969950D01*
X38886D01*
G03X36112I-1387J-2201D01*
G01X20927D01*
G02X20644Y1970633I0J400D01*
G01X26859Y1976848D01*
X31126D01*
X31153Y1976840D01*
G03Y1981260I646J2210D01*
G01X31126Y1981252D01*
X25035D01*
X6302Y1962518D01*
Y1958087D01*
G03Y1955313I2201J-1387D01*
G01Y1949685D01*
G02X5813Y1949295I-400J0D01*
G03X3851Y1948836I-510J-2245D01*
G02X3199Y1949147I-252J311D01*
G01Y1988199D01*
X4000Y1989000D01*
X1029000D01*
X1030000Y1988000D01*
X1029999D01*
Y1745050D01*
X1030000Y1745049D01*
Y1696500D01*
X1028420Y1694920D01*
G02X1027740Y1695158I-283J283D01*
G03X1018345Y1685763I-8449J-946D01*
G02X1018583Y1685083I-45J-397D01*
G01X1013450Y1679950D01*
Y1675350D01*
X1012700Y1674600D01*
X975500D01*
X973901Y1673001D01*
X973827Y1672995D01*
G03X973381Y1668483I174J-2295D01*
G01X973431Y1668469D01*
X974400Y1667500D01*
X975748D01*
X975790Y1667356D01*
G03X980210I2210J644D01*
G01X980252Y1667500D01*
X981902D01*
X981916Y1667316D01*
G03X986506I2295J184D01*
G01X986520Y1667500D01*
X1015500D01*
X1016000Y1667000D01*
Y1664900D01*
X1015600Y1664500D01*
X993000D01*
X991500Y1663000D01*
Y1662522D01*
X983586D01*
X982788Y1663320D01*
X978312D01*
X977778Y1662787D01*
X977686Y1662794D01*
G03X978576Y1658465I-186J-2294D01*
G02X978840Y1658393I94J-177D01*
G03X983099Y1659491I1960J1207D01*
G01X983108Y1659682D01*
X991500D01*
Y1659000D01*
X993000Y1657500D01*
X1015300D01*
X1015900Y1656900D01*
Y1655300D01*
X1015100Y1654500D01*
X983246D01*
G03X979754I-1746J-1500D01*
G01X975400D01*
X973422Y1652522D01*
X969410D01*
G03X969413Y1649682I-1810J-1422D01*
G01X972400D01*
Y1649166D01*
G02X971935Y1648771I-400J0D01*
G03Y1644229I-377J-2271D01*
G02X972400Y1643834I65J-395D01*
G01Y1637992D01*
G02X972059Y1637850I-200J0D01*
G01X971887Y1638022D01*
X971894Y1638114D01*
G03X969786Y1636006I-2294J186D01*
G01X969878Y1636013D01*
X971210Y1634682D01*
X972400D01*
Y1624100D01*
X974000Y1622500D01*
X985860D01*
G03X988340I1240J2400D01*
G01X1014700D01*
X1015400Y1621800D01*
Y1620800D01*
X1014100Y1619500D01*
X988000D01*
X984600Y1616100D01*
Y1611800D01*
X987600Y1608800D01*
X1014000D01*
X1016100Y1606700D01*
Y1514700D01*
X1015000Y1513600D01*
X950100D01*
X944500Y1508000D01*
Y1434500D01*
X950400Y1428600D01*
X1017400D01*
X1020200Y1425800D01*
X1028200D01*
X1030000Y1424000D01*
Y1270500D01*
X1029999D01*
Y4000D01*
X1028999Y3000D01*
X139725D01*
G02X139499Y3730I0J400D01*
G03X120341I-9579J13986D01*
G02X120115Y3000I-226J-330D01*
G01X3999D01*
G37*
G36*
G01X50750Y143123D02*
Y132477D01*
G03Y128623I1749J-1927D01*
G01Y113750D01*
X47500Y110500D01*
X31500D01*
X27500Y114500D01*
Y169500D01*
X22500Y174500D01*
X20862D01*
Y174666D01*
X5334D01*
X5100Y174900D01*
Y200960D01*
X20862D01*
Y201500D01*
X36500D01*
X50750Y187250D01*
Y164477D01*
G03Y160623I1749J-1927D01*
G01Y146977D01*
G03Y143123I1749J-1927D01*
G37*
G36*
G01X5499Y689650D02*
X5299Y689850D01*
Y710850D01*
X7102Y712653D01*
X7231Y712587D01*
G03X7558Y722989I2612J5124D01*
G02X6999Y723356I-159J367D01*
G01Y741550D01*
X10999Y745550D01*
X11000D01*
X11950Y746500D01*
X56499D01*
X58999Y744000D01*
Y724500D01*
X31084Y696585D01*
X30958Y696643D01*
G03X28418Y696223I-959J-2093D01*
G02X27826Y696271I-274J291D01*
G03X26624Y692654I-1827J-1401D01*
G01X26737Y692686D01*
X26961Y692462D01*
X26549Y692050D01*
X22999D01*
X20599Y689650D01*
X5499D01*
G37*
G36*
G01X5500Y1096000D02*
X3001Y1098499D01*
Y1184001D01*
X4000Y1185000D01*
X46000D01*
X52500Y1178500D01*
Y1102000D01*
X47250Y1096750D01*
X31250D01*
X30500Y1096000D01*
X5500D01*
G37*
G36*
G01X5099Y1693650D02*
X7972Y1696523D01*
X8088Y1696486D01*
G03X15593Y1701854I1755J5477D01*
G01X15597Y1702050D01*
X19461D01*
G03X23739I2139J850D01*
G01X53499D01*
X63500Y1692049D01*
Y1641760D01*
G03Y1636430I3248J-2665D01*
G01Y1629050D01*
X70499Y1622051D01*
Y1622050D01*
X71499Y1621050D01*
X90999D01*
X96999Y1615050D01*
Y1588550D01*
X95999Y1587550D01*
X78999D01*
X75999Y1590550D01*
X45499D01*
X36999Y1599050D01*
Y1614824D01*
X37014Y1614861D01*
G03Y1616607I-2130J873D01*
G01X36999Y1616644D01*
Y1630222D01*
X37009Y1630252D01*
G03Y1631654I-2193J701D01*
G01X36999Y1631684D01*
Y1663208D01*
G03Y1663392I-2300J92D01*
G01Y1671050D01*
X34991Y1673058D01*
X34997Y1673148D01*
G03X32233Y1675554I-2297J152D01*
G01X32213Y1675550D01*
X24004D01*
G03X21768Y1675574I-1140J-2000D01*
G01X21723Y1675550D01*
X21699D01*
X21663Y1675514D01*
X21644Y1675502D01*
G03X20912Y1674770I1220J-1952D01*
G01X20900Y1674751D01*
X20006Y1673856D01*
X5392D01*
X5099Y1674150D01*
Y1693650D01*
G37*
G36*
G01X15450Y1703252D02*
X15412Y1703401D01*
G03X4568Y1704254I-5569J-1438D01*
G02X3918Y1704131I-367J160D01*
G01X3499Y1704550D01*
Y1754250D01*
X5299Y1756050D01*
X40135D01*
G02X40452Y1755406I0J-400D01*
G03X40025Y1753511I1823J-1406D01*
G02X39541Y1753038I-391J-84D01*
G03X38758Y1748511I-540J-2238D01*
G02X39084Y1747956I-42J-398D01*
G03X41442Y1749339I2116J-906D01*
G02X41116Y1749894I42J398D01*
G03X41250Y1751289I-2116J907D01*
G02X41734Y1751762I391J84D01*
G03X43825Y1755702I541J2238D01*
G01X43759Y1755762D01*
Y1756050D01*
X44142D01*
X44200Y1755994D01*
G03X47454Y1756050I1599J1656D01*
G01X60999D01*
X78999Y1738050D01*
Y1703050D01*
X99499Y1682550D01*
Y1655550D01*
X102610Y1652440D01*
Y1624160D01*
X100999Y1622550D01*
X73499D01*
X64999Y1631050D01*
Y1634696D01*
G02X65516Y1635078I400J0D01*
G03X66748Y1634894I1230J4017D01*
G01X71048D01*
G03Y1643296I0J4201D01*
G01X66748D01*
G03X65516Y1643112I-2J-4201D01*
G02X64999Y1643494I-117J382D01*
G01Y1693050D01*
X55652Y1702397D01*
G02X55935Y1703080I283J283D01*
G01X63912D01*
X65452Y1701539D01*
X65435Y1701437D01*
G03X68437Y1698435I2565J-437D01*
G01X68539Y1698452D01*
X72835Y1694156D01*
G02X72841Y1693596I-283J-283D01*
G03X75920Y1693811I1658J-1596D01*
G01Y1695088D01*
X70548Y1700461D01*
X70565Y1700563D01*
G03X67563Y1703565I-2565J437D01*
G01X67461Y1703548D01*
X65088Y1705920D01*
X22612D01*
X21878Y1705187D01*
X21786Y1705194D01*
G03X19355Y1703407I-186J-2294D01*
G01X19319Y1703252D01*
X15450D01*
G37*
G36*
G01X3924Y1912996D02*
G02X3199Y1913228I-325J232D01*
G01Y1933622D01*
G02X3882Y1933905I400J0D01*
G01X11207Y1926580D01*
X16068D01*
G03X16826Y1926256I1389J2200D01*
G01X16880Y1926243D01*
X20750Y1922372D01*
X20740Y1922277D01*
G03X21369Y1920444I2290J-239D01*
G02X21003Y1919775I-289J-277D01*
G03X3924Y1912996I-3284J-16631D01*
G37*
G36*
G01X130598Y238290D02*
G02X127911Y239402I0J3802D01*
G01X127232Y240082D01*
X74282Y293033D01*
G02X73788Y294223I1189J1191D01*
G01Y305889D01*
G02X74504Y306135I400J1D01*
G03X74929Y305653I4098J3185D01*
G01X125013Y255570D01*
X125110Y255473D01*
Y252740D01*
X124727D01*
X124703Y252952D01*
X124700Y252951D01*
X124666Y253130D01*
G03X120092Y252524I-2269J-442D01*
G01X120098Y252433D01*
X120090Y252426D01*
X120493Y248886D01*
X120496Y248887D01*
X120530Y248708D01*
G03X125021Y248515I2269J442D01*
G01X125063Y248660D01*
X125499D01*
G03X128572Y250308I0J3689D01*
G02X129277Y250234I333J-222D01*
G03X130274Y248525I6149J2442D01*
G03X130746Y247998I5157J4144D01*
G01X137347Y241397D01*
G03X140334Y240160I2988J2989D01*
G01X147688D01*
Y239729D01*
G03X147864Y238843I2311J-1D01*
G02X147495Y238290I-369J-153D01*
G01X130598D01*
G37*
G36*
G01X34224Y461324D02*
X29499Y466050D01*
Y491050D01*
X32455Y494006D01*
X37002D01*
G03X37975Y494049I-99J13281D01*
G01X37983Y494050D01*
X41999D01*
X44027Y496078D01*
X44045Y496089D01*
G03X45627Y497272I-7140J11198D01*
G03X45697Y497337I-910J1051D01*
G01X62627Y514268D01*
G02X63308Y514025I283J-283D01*
G03X64178Y512439I2291J225D01*
G01Y509813D01*
X80312Y493680D01*
X81815D01*
X81865Y493630D01*
X121819D01*
G03X126179I2180J1420D01*
G01X170898D01*
G02X171135Y492907I0J-400D01*
G03X173863I1364J-1854D01*
G02X174100Y493630I237J323D01*
G01X174501D01*
X174530Y493463D01*
G03X176613Y496144I2269J387D01*
G01X176521Y496137D01*
X176187Y496470D01*
X175727D01*
G02X175334Y496946I0J400D01*
G02X177184Y498778I2261J-433D01*
G03X177395Y498889I-72J393D01*
G02X177961I283J-283D01*
G01X186798Y490052D01*
Y486463D01*
G03X186525Y486268I1198J-1966D01*
G02X185994Y486285I-256J307D01*
G03X186090Y482612I-1794J-1885D01*
G02X186620Y482657I290J-275D01*
G03X190279Y484177I1380J1843D01*
G01X190304Y484348D01*
X191568D01*
G02X191851Y483666I0J-400D01*
G01X183185Y475000D01*
X182400D01*
X175469Y468069D01*
G02X175378Y468030I-3230J7411D01*
G01X43340D01*
X36634Y461324D01*
X34224D01*
G37*
G36*
G01X101232Y1473290D02*
G03Y1468810I-533J-2240D01*
G02X101724Y1468421I92J-389D01*
G01Y1441724D01*
X100500Y1440500D01*
X99548D01*
X53870Y1486179D01*
G02X52499Y1488431I6286J5370D01*
G01Y1513050D01*
X50595Y1514954D01*
X50581Y1514978D01*
G03X49323Y1516714I-8623J-4925D01*
G01X49305Y1516734D01*
X49288Y1516767D01*
X41500Y1524554D01*
Y1533018D01*
X42670Y1534188D01*
X57753D01*
G03X60520Y1532950I2247J1312D01*
G01X60596Y1532874D01*
X77174D01*
X101724Y1508324D01*
Y1473679D01*
G02X101232Y1473290I-400J0D01*
G37*
G36*
G01X87026Y1909026D02*
X93000Y1915000D01*
Y1946551D01*
X101999Y1955550D01*
X131999D01*
X137499Y1950050D01*
Y1910050D01*
X130499Y1903050D01*
X117999D01*
X106999Y1892050D01*
Y1867050D01*
X103999Y1864050D01*
X83499D01*
X79999Y1867550D01*
Y1876550D01*
X78999Y1877550D01*
X56999D01*
X54499Y1880050D01*
Y1898550D01*
X61499Y1905550D01*
X72999D01*
X76474Y1909026D01*
X87026D01*
G37*
G36*
G01X17796Y1935733D02*
X20500Y1938438D01*
Y1957662D01*
X19200Y1958962D01*
Y1959498D01*
X19248Y1959554D01*
G03X19766Y1960653I-1749J1496D01*
G01X19777Y1960715D01*
X21410Y1962348D01*
X30684D01*
G02X31026Y1961741I0J-400D01*
G03X30789Y1959909I1973J-1187D01*
G01X30798Y1959882D01*
Y1958242D01*
G03X35200I2201J-1387D01*
G01Y1959882D01*
X35209Y1959909D01*
G03X34972Y1961741I-2210J645D01*
G02X35314Y1962348I342J207D01*
G01X39161D01*
X41429Y1960079D01*
X41443Y1960054D01*
G03X44259Y1959000I2019J1106D01*
G02X44798Y1958625I139J-375D01*
G01Y1955052D01*
X46501Y1953348D01*
X54000D01*
Y1953000D01*
X56500Y1950500D01*
Y1949500D01*
X56000Y1949000D01*
Y1945000D01*
X52000Y1941000D01*
X44500D01*
X42000Y1938500D01*
Y1928128D01*
G02X41317Y1927845I-400J0D01*
G01X38059Y1931103D01*
X38046Y1931157D01*
G03X36150Y1933053I-2525J-629D01*
G01X36096Y1933066D01*
X27700Y1941462D01*
Y1955377D01*
X27709Y1955404D01*
G03X23289I-2210J646D01*
G01X23298Y1955377D01*
Y1939638D01*
X27202Y1935733D01*
G02X26919Y1935050I-283J-283D01*
G01X25386D01*
G03X22612I-1387J-2201D01*
G01X18079D01*
G02X17796Y1935733I0J400D01*
G37*
G36*
G01X32768Y1912445D02*
G02X32031Y1912231I-400J1D01*
G03X23582Y1919050I-14310J-9087D01*
G02X23618Y1919812I138J375D01*
G03X24580Y1920336I-589J2226D01*
G02X25133Y1920322I269J-296D01*
G03X27411Y1919735I1633J1623D01*
G01X27438Y1919744D01*
X28679D01*
X32768Y1915654D01*
Y1912445D01*
G37*
G36*
G01X46999Y1954550D02*
X45999Y1955550D01*
Y1965050D01*
X50499Y1969550D01*
X96999D01*
X99499Y1972050D01*
X108999D01*
X112499Y1968550D01*
Y1959050D01*
X110999Y1957550D01*
X94499D01*
X91499Y1954550D01*
X46999D01*
G37*
G36*
G01X55449Y1937000D02*
X69499Y1951050D01*
X84499D01*
X89499Y1946050D01*
Y1917050D01*
X84999Y1912550D01*
X75499D01*
X71974Y1909026D01*
X59975D01*
X55499Y1904550D01*
X47000D01*
X45500Y1906050D01*
Y1936500D01*
X46000Y1937000D01*
X55449D01*
G37*
G36*
G01X570872Y552111D02*
X283600Y437400D01*
X275700Y435700D01*
X169700Y435524D01*
Y443434D01*
X180179Y452124D01*
X181436Y453165D01*
X181899Y453445D01*
X182329Y453616D01*
X826584Y655854D01*
X826830Y655608D01*
G02X826697Y654954I-283J-283D01*
G01X802504Y645224D01*
X802502Y645223D01*
G03X802451Y645203I482J-1303D01*
G01X802449Y645202D01*
X798097Y643427D01*
X570872Y552111D01*
G37*
G36*
G01X190049Y485550D02*
G03X188000Y486802I-2049J-1051D01*
G01X187999D01*
Y490550D01*
X158999Y519550D01*
X146499D01*
X143499Y522550D01*
Y533550D01*
X144499Y534550D01*
X158499D01*
X197499Y495550D01*
Y489550D01*
X193499Y485550D01*
X190049D01*
G37*
G36*
G01X818677Y1453544D02*
X820037Y1455223D01*
X834131Y1469317D01*
G02X835443Y1469860I1311J-1311D01*
G01X844780D01*
G02X844994Y1469123I-1J-400D01*
G03X844227Y1468509I2403J-3788D01*
G01X833685Y1457967D01*
X157208Y633078D01*
G02X156499Y633332I-309J254D01*
G01Y636519D01*
X818578Y1453423D01*
X818677Y1453544D01*
G37*
G36*
G01X116999Y1957550D02*
X115999Y1958550D01*
Y1983550D01*
X118499Y1986050D01*
X126339D01*
G03X130661I2161J1450D01*
G01X135999D01*
X139499Y1982550D01*
Y1958550D01*
X138499Y1957550D01*
X116999D01*
G37*
G36*
G01X1016200Y1432800D02*
X1014700Y1431300D01*
X952200D01*
X948000Y1435500D01*
Y1506800D01*
X952200Y1511000D01*
X1015400D01*
X1016200Y1510200D01*
Y1432800D01*
G37*
%LPC*%
G75*
G36*
G01X774074Y1973765D02*
G03X773541Y1973767I-268J-298D01*
G02X773554Y1977647I-1727J1946D01*
G03X774087Y1977645I268J298D01*
G02X774074Y1973765I1727J-1946D01*
G37*
G36*
G01X782091Y1969163D02*
G03Y1969763I-264J300D01*
G02X781964Y1973542I1723J1950D01*
G03X781991Y1974075I-285J282D01*
G02X785866Y1973879I2025J1633D01*
G03X785839Y1973346I285J-282D01*
G02X785537Y1969763I-2025J-1634D01*
G03Y1969163I264J-300D01*
G02X782091I-1723J-1950D01*
G37*
G36*
G01X262298Y1966663D02*
G02X266700I2201J1387D01*
G01Y1964723D01*
X266709Y1964696D01*
G02X262289I-2210J-646D01*
G01X262298Y1964723D01*
Y1966663D01*
G37*
G36*
G01X291449Y1972773D02*
G03X292049I300J264D01*
G02X295722Y1969100I1950J-1723D01*
G03Y1968500I264J-300D01*
G02Y1964600I-1723J-1950D01*
G03Y1964000I264J-300D01*
G02X292237Y1960135I-1723J-1950D01*
G03X291638Y1960068I-270J-295D01*
G02X288059Y1963717I-2139J1482D01*
G03Y1964383I-222J333D01*
G02X287776Y1968500I1440J2167D01*
G03Y1969100I-264J300D01*
G02X291449Y1972773I1723J1950D01*
G37*
G36*
G01X307630Y1964006D02*
G03X307697Y1963473I327J-230D01*
G02X303870Y1962994I-1697J-1973D01*
G03X303803Y1963527I-327J230D01*
G02X307630Y1964006I1697J1973D01*
G37*
G36*
G01X798668Y1961858D02*
X798722Y1961871D01*
X801002Y1964152D01*
X801426D01*
X801453Y1964160D01*
G02X802893Y1959789I646J-2210D01*
G01X802851Y1959774D01*
X801835Y1958758D01*
X801822Y1958704D01*
G02X798668Y1961858I-2525J629D01*
G37*
G36*
G01X216075Y1952449D02*
X215995Y1952447D01*
X215171Y1951622D01*
X215157Y1951597D01*
G02X212032Y1954722I-2019J1106D01*
G01X212057Y1954736D01*
X213876Y1956554D01*
X213885Y1956567D01*
G02X214482Y1957164I2114J-1517D01*
G01X214495Y1957173D01*
X214573Y1957252D01*
X214611D01*
X214658Y1957280D01*
G02X216075Y1952449I1341J-2230D01*
G37*
G36*
G01X793392Y1951821D02*
X793919Y1951293D01*
Y1950861D01*
G02X790268Y1949617I-1420J-1811D01*
G03X790129Y1949858I-194J49D01*
G02X793409Y1951923I715J2502D01*
G01X793392Y1951821D01*
G37*
G36*
G01X837316Y1946353D02*
X836832Y1945869D01*
X836818Y1945844D01*
G02X832912Y1948269I-2018J1107D01*
G01Y1949763D01*
G02X837316I2202J1387D01*
G01Y1946353D01*
G37*
G36*
G01X344371Y1945560D02*
G03X344315Y1944968I238J-321D01*
G02X341249Y1945258I-1694J-1559D01*
G03X341305Y1945850I-238J321D01*
G02X344371Y1945560I1694J1559D01*
G37*
G36*
G01X208798Y1944363D02*
G02X213200I2201J1387D01*
G01Y1942723D01*
X213209Y1942696D01*
G02X208789I-2210J-646D01*
G01X208798Y1942723D01*
Y1944363D01*
G37*
G36*
G01X333554Y1946346D02*
G03X333515Y1946077I126J-156D01*
G02X333294Y1943184I-1893J-1310D01*
G03X333306Y1942622I290J-275D01*
G02X329809Y1942729I-1807J-1872D01*
G03X329857Y1943290I-259J305D01*
G02X330171Y1946554I1765J1477D01*
G03X330210Y1946823I-126J156D01*
G02X333554Y1946346I1893J1310D01*
G37*
G36*
G01X866616Y1942662D02*
Y1941438D01*
X866644Y1941391D01*
G02X862184I-2230J-1341D01*
G01X862212Y1941438D01*
Y1942662D01*
X862184Y1942709D01*
G02X866644I2230J1341D01*
G01X866616Y1942662D01*
G37*
G36*
G01X251709Y1927404D02*
X251700Y1927377D01*
Y1925737D01*
G02X247298I-2201J-1387D01*
G01Y1927377D01*
X247289Y1927404D01*
G02X251709I2210J646D01*
G37*
G36*
G01X859613Y1915298D02*
X857102D01*
X856958Y1915352D01*
X856930Y1915354D01*
G02X858143Y1919702I169J2296D01*
G01X859613D01*
G02Y1915298I1387J-2202D01*
G37*
G36*
G01X268722Y1918100D02*
G03Y1917500I264J-300D01*
G02X265276I-1723J-1950D01*
G03Y1918100I-264J300D01*
G02Y1922000I1723J1950D01*
G03Y1922600I-264J300D01*
G02Y1926500I1723J1950D01*
G03Y1927100I-264J300D01*
G02Y1931000I1723J1950D01*
G03Y1931600I-264J300D01*
G02X268722I1723J1950D01*
G03Y1931000I264J-300D01*
G02Y1927100I-1723J-1950D01*
G03Y1926500I264J-300D01*
G02Y1922600I-1723J-1950D01*
G03Y1922000I264J-300D01*
G02Y1918100I-1723J-1950D01*
G37*
G36*
G01X229798Y1916663D02*
G02X234200I2201J1387D01*
G01Y1914723D01*
X234209Y1914696D01*
G02X229789I-2210J-646D01*
G01X229798Y1914723D01*
Y1916663D01*
G37*
G36*
G01X809659Y1912915D02*
G03Y1912315I264J-300D01*
G02X806213I-1723J-1950D01*
G03Y1912915I-264J300D01*
G02X806026Y1916632I1723J1950D01*
G03X806035Y1917165I-294J272D01*
G02X806061Y1920595I1970J1700D01*
G03X806060Y1921128I-299J266D01*
G02X809941Y1921135I1937J1737D01*
G03X809942Y1920602I299J-266D01*
G02X809915Y1917098I-1937J-1737D01*
G03X809906Y1916565I294J-272D01*
G02X809659Y1912915I-1970J-1700D01*
G37*
G36*
G01X212798Y1912663D02*
G02X217200I2201J1387D01*
G01Y1910223D01*
X217209Y1910196D01*
G02X212789I-2210J-646D01*
G01X212798Y1910223D01*
Y1912663D01*
G37*
G36*
G01X793709Y1919582D02*
G03X793708Y1920162I-276J290D01*
G02X797291Y1920164I1790J1888D01*
G03X797292Y1919584I276J-290D01*
G02X797438Y1915959I-1791J-1888D01*
G03X797437Y1915426I298J-267D01*
G02X797448Y1911978I-1944J-1730D01*
G03X797452Y1911446I300J-264D01*
G02X793571Y1911414I-1926J-1750D01*
G03X793567Y1911946I-300J264D01*
G02X793556Y1915433I1926J1750D01*
G03X793557Y1915966I-298J267D01*
G02X793709Y1919582I1944J1729D01*
G37*
G36*
G01X865900Y1905777D02*
Y1904137D01*
G02X861498I-2201J-1387D01*
G01Y1905777D01*
X861489Y1905804D01*
G02X865909I2210J646D01*
G01X865900Y1905777D01*
G37*
G36*
G01X220460Y1930947D02*
Y1939039D01*
X224735Y1943314D01*
G02X229263Y1938786I2264J-2264D01*
G01X226864Y1936387D01*
Y1928295D01*
X226638Y1928069D01*
Y1890465D01*
G02X226621Y1890136I-3202J1D01*
G03X227136Y1889713I398J-41D01*
G02X229671Y1888873I678J-2200D01*
G03X230261Y1888812I323J237D01*
G02X229943Y1885740I1539J-1712D01*
G03X229353Y1885801I-323J-237D01*
G02X225520Y1887317I-1539J1712D01*
G03X224935Y1887636I-398J-35D01*
G02X220234Y1890465I-1499J2829D01*
G01Y1930721D01*
X220460Y1930947D01*
G37*
G36*
G01X220310Y1885754D02*
X220302Y1885727D01*
Y1884087D01*
G02X215898I-2202J-1387D01*
G01Y1885727D01*
X215890Y1885754D01*
G02X220310I2210J646D01*
G37*
G36*
G01X232010Y1875054D02*
X232002Y1875027D01*
Y1873387D01*
G02X227598I-2202J-1387D01*
G01Y1875027D01*
X227590Y1875054D01*
G02X232010I2210J646D01*
G37*
G36*
G01X44509Y1860701D02*
X44462Y1860731D01*
X41475Y1860798D01*
X41173D01*
X41146Y1860790D01*
G02Y1865210I-646J2210D01*
G01X41173Y1865202D01*
X41525D01*
X44562Y1865132D01*
X44610Y1865160D01*
G02X44509Y1860701I1290J-2260D01*
G37*
G36*
G01X643642Y1816423D02*
G03X643466Y1817016I-331J224D01*
G02X646267Y1817848I894J2121D01*
G03X646443Y1817255I331J-224D01*
G02X643642Y1816423I-894J-2121D01*
G37*
G36*
G01X796035Y1807794D02*
X796127Y1807787D01*
X799078Y1810738D01*
Y1820295D01*
X801213Y1822430D01*
X801206Y1822522D01*
G02X805299Y1824144I2294J186D01*
G03X805579Y1824111I157J124D01*
G02X806814Y1820006I1421J-1811D01*
G01X806722Y1820013D01*
X803820Y1817111D01*
Y1808774D01*
X797125Y1802080D01*
X794811D01*
G02X791189I-1811J1420D01*
G01X759612D01*
X741003Y1820688D01*
X713463D01*
G02X710056Y1823768I-1811J1421D01*
G03X710072Y1824040I-138J145D01*
G02X713659Y1826924I1776J1464D01*
G01X741472D01*
X761476Y1806920D01*
X794038D01*
G02X796035Y1807794I1811J-1420D01*
G37*
G36*
G01X881191Y1784546D02*
G03X881185Y1783941I259J-305D01*
G02X878173Y1783967I-1521J-1728D01*
G03X878179Y1784572I-259J305D01*
G02X881191Y1784546I1521J1728D01*
G37*
G36*
G01X346212Y1762328D02*
X300534Y1808006D01*
X300432Y1807989D01*
G02X297430Y1810991I-437J2565D01*
G01X297447Y1811093D01*
X288578Y1819962D01*
Y1865155D01*
G03X287896Y1865438I-400J0D01*
G01X249800Y1827342D01*
X249817Y1827240D01*
G02X246815Y1824238I-2565J-437D01*
G01X246713Y1824255D01*
X203786Y1781328D01*
X203793Y1781236D01*
G02X201685Y1783344I-2294J-186D01*
G01X201777Y1783337D01*
X244704Y1826264D01*
X244687Y1826366D01*
G02X247689Y1829368I2565J437D01*
G01X247791Y1829351D01*
X286940Y1868500D01*
Y1880838D01*
G03X286197Y1881043I-400J0D01*
G02Y1898473I-14540J8715D01*
G03X286940Y1898678I343J205D01*
G01Y1926600D01*
X285777Y1927763D01*
X285685Y1927756D01*
G02X284894Y1927829I-187J2294D01*
G03X284418Y1927590I-104J-386D01*
G02X283439Y1926383I-2418J961D01*
G03Y1925717I222J-333D01*
G02Y1921383I-1440J-2167D01*
G03Y1920717I222J-333D01*
G02X280559I-1440J-2167D01*
G03Y1921383I-222J333D01*
G02Y1925717I1440J2167D01*
G03Y1926383I-222J333D01*
G02X282972Y1930963I1441J2167D01*
G03X283474Y1931144I150J371D01*
G02X287793Y1929864I2025J-1095D01*
G01X287786Y1929772D01*
X287896Y1929662D01*
G03X288578Y1929945I282J283D01*
G01Y1945737D01*
X288405Y1945760D01*
G02X287286Y1946233I305J2282D01*
G03X286736Y1946181I-248J-314D01*
G02X286422Y1949500I-1737J1510D01*
G03X286972Y1949552I248J314D01*
G02X291003Y1947856I1737J-1510D01*
G01X290996Y1947764D01*
X291420Y1947340D01*
Y1935114D01*
G03X292110Y1934839I400J0D01*
G02X296138Y1934532I1889J-1789D01*
G03X296737Y1934465I329J228D01*
G02X300233Y1934490I1762J-1915D01*
G03X300765I266J299D01*
G02X304449Y1934273I1734J-1940D01*
G03X305049I300J264D01*
G02Y1930827I1950J-1723D01*
G03X304449I-300J-264D01*
G02X300765Y1930610I-1950J1723D01*
G03X300233I-266J-299D01*
G02X296360Y1931068I-1734J1940D01*
G03X295761Y1931135I-329J-228D01*
G02X292110Y1931261I-1762J1915D01*
G03X291420Y1930986I-290J-275D01*
G01Y1821138D01*
X299456Y1813102D01*
X299558Y1813119D01*
G02X302560Y1810117I437J-2565D01*
G01X302543Y1810015D01*
X348221Y1764337D01*
X348313Y1764344D01*
G02X346205Y1762236I186J-2294D01*
G01X346212Y1762328D01*
G37*
G36*
G01X884196Y1746470D02*
G03X884755Y1746416I307J256D01*
G02X884404Y1742730I1645J-2016D01*
G03X883845Y1742784I-307J-256D01*
G02X884196Y1746470I-1645J2016D01*
G37*
G36*
G01X873308Y1743446D02*
X873321Y1743392D01*
X875502Y1741212D01*
Y1740773D01*
X875510Y1740746D01*
G02X871131Y1739328I-2210J-646D01*
G01X871116Y1739370D01*
X870208Y1740279D01*
X870154Y1740292D01*
G02X873308Y1743446I629J2525D01*
G37*
G36*
G01X162813Y1729123D02*
G03X163079Y1729656I-106J386D01*
G02X167542Y1732225I2420J958D01*
G03X168208Y1732283I314J248D01*
G02X172755Y1729753I2291J-1233D01*
G03X173021Y1729162I347J-199D01*
G02X170549Y1724890I-522J-2549D01*
G03X169949I-300J-264D01*
G02X166049I-1950J1723D01*
G03X165449I-300J-264D01*
G02X162813Y1729123I-1950J1723D01*
G37*
G36*
G01X888640Y1719812D02*
Y1718273D01*
X888649Y1718246D01*
G02X884229I-2210J-646D01*
G01X884238Y1718273D01*
Y1720026D01*
G02X888640Y1719812I2268J1274D01*
G37*
G36*
G01X170314Y1712637D02*
G03X169648Y1712646I-336J-217D01*
G02X165332Y1712673I-2149J1467D01*
G03X164666I-333J-222D01*
G02Y1715553I-2167J1440D01*
G03X165332I333J222D01*
G02X169684Y1715526I2167J-1440D01*
G03X170350Y1715517I336J217D01*
G02X170314Y1712637I2149J-1467D01*
G37*
G36*
G01X860767Y1711619D02*
X859754Y1712632D01*
X859690Y1712642D01*
G02X862527Y1716113I395J2572D01*
G01X862542Y1716071D01*
X863881Y1714733D01*
X863906Y1714719D01*
G02X860781Y1711594I-1106J-2019D01*
G01X860767Y1711619D01*
G37*
G36*
G01X893092Y1711679D02*
X891833Y1710419D01*
X891819Y1710394D01*
G02X888694Y1713519I-2019J1106D01*
G01X888719Y1713533D01*
X889979Y1714792D01*
X889992Y1714846D01*
G02X893146Y1711692I2525J-629D01*
G01X893092Y1711679D01*
G37*
G36*
G01X353598Y1712750D02*
X353686Y1712746D01*
X362911Y1721970D01*
X525911D01*
X740411Y1936470D01*
X753819D01*
G02X758179I2180J-1420D01*
G01X769190D01*
X769200Y1936661D01*
G02X769854Y1938160I2299J-111D01*
G03Y1938440I-143J140D01*
G02X769271Y1940629I1645J1610D01*
G03X768884Y1941130I-387J101D01*
G01X758679D01*
G02X754319I-2180J1420D01*
G01X733562D01*
X526062Y1733630D01*
X387310D01*
G02Y1736470I-1811J1420D01*
G01X524886D01*
X732386Y1943970D01*
X754319D01*
G02X758679I2180J-1420D01*
G01X793587D01*
X794221Y1943337D01*
X794313Y1943344D01*
G02X792200Y1940939I186J-2294D01*
G01X792190Y1941130D01*
X778123D01*
G03X777733Y1940639I0J-400D01*
G02X774253Y1937626I-2534J-589D01*
G03X773722Y1937149I-145J-373D01*
G02X771313Y1934256I-2223J-599D01*
G01X771221Y1934263D01*
X770587Y1933630D01*
X758179D01*
G02X753819I-2180J1420D01*
G01X741587D01*
X527087Y1719130D01*
X364087D01*
X355774Y1710816D01*
X355785Y1710720D01*
G02X353598Y1712750I-2286J-270D01*
G37*
G36*
G01X170943Y1684420D02*
G03X170983Y1684141I160J-119D01*
G02X167757Y1683680I-1383J-1841D01*
G03X167717Y1683959I-160J119D01*
G02X170943Y1684420I1383J1841D01*
G37*
G36*
G01X963658Y1636924D02*
G03X963199Y1636509I-59J-396D01*
G02X961242Y1638676I-2299J-109D01*
G03X961701Y1639091I59J396D01*
G02X963658Y1636924I2299J109D01*
G37*
G36*
G01X178163Y1628036D02*
G03X178088Y1628574I-328J228D01*
G02X178057Y1632581I1645J2016D01*
G03X178133Y1633108I-257J306D01*
G02X181975Y1632559I2166J1442D01*
G03X181899Y1632032I257J-306D01*
G02X181869Y1629104I-2166J-1442D01*
G03X181944Y1628566I328J-228D01*
G02X178163Y1628036I-1645J-2016D01*
G37*
G36*
G01X197315Y1621743D02*
G03X197328Y1621130I263J-301D01*
G02X193985Y1621057I-1628J-2030D01*
G03X193972Y1621670I-263J301D01*
G02X195291Y1626284I1628J2030D01*
G03X195527Y1626964I-47J397D01*
G01X180277Y1642213D01*
X180185Y1642206D01*
G02X182293Y1644314I-186J2294D01*
G01X182286Y1644222D01*
X197871Y1628637D01*
X198011Y1628756D01*
G02X198644Y1624863I1489J-1756D01*
G03X198110Y1624386I-148J-371D01*
G02X197315Y1621743I-2510J-686D01*
G37*
G36*
G01X159874Y1596221D02*
G03X159650Y1596065I-28J-198D01*
G02X157726Y1598829I-2250J485D01*
G03X157950Y1598985I28J198D01*
G02X159874Y1596221I2250J-485D01*
G37*
G36*
G01X291732Y1580054D02*
G03X292264I266J299D01*
G02X295721Y1576164I1734J-1940D01*
G03Y1575564I264J-300D01*
G02Y1571664I-1723J-1950D01*
G03Y1571064I264J-300D01*
G02X292264Y1567174I-1723J-1950D01*
G03X291732I-266J-299D01*
G02X288275Y1571064I-1734J1940D01*
G03Y1571664I-264J300D01*
G02Y1575564I1723J1950D01*
G03Y1576164I-264J300D01*
G02X291732Y1580054I1723J1950D01*
G37*
G36*
G01X787550Y1563846D02*
G03Y1563246I264J-300D01*
G02X784104I-1723J-1950D01*
G03Y1563846I-264J300D01*
G02X783374Y1566665I1723J1950D01*
G03X782975Y1567198I-377J134D01*
G02X780877Y1568073I-148J2598D01*
G03X780277I-300J-264D01*
G02X776377I-1950J1723D01*
G03X775777I-300J-264D01*
G02X775524Y1567823I-1951J1722D01*
G03X775457Y1567290I260J-303D01*
G02X771630Y1567769I-2130J-1494D01*
G03X771697Y1568302I-260J303D01*
G02X775777Y1571519I2130J1494D01*
G03X776377I300J264D01*
G02X780277I1950J-1723D01*
G03X780877I300J264D01*
G02X785280Y1568927I1950J-1723D01*
G03X785679Y1568394I377J-134D01*
G02X787550Y1563846I148J-2598D01*
G37*
G36*
G01X281609Y1557695D02*
G03X281889I140J143D01*
G02X284148Y1558259I1611J-1645D01*
G03X284394Y1558389I56J192D01*
G02X286402Y1555022I2474J-807D01*
G01X286299Y1555041D01*
X285887Y1554630D01*
X285310D01*
G02X281889Y1554405I-1811J1420D01*
G03X281609I-140J-143D01*
G02Y1557695I-1610J1645D01*
G37*
G36*
G01X807100Y1556277D02*
Y1554637D01*
G02X802698I-2201J-1387D01*
G01Y1556277D01*
X802689Y1556304D01*
G02X807109I2210J646D01*
G01X807100Y1556277D01*
G37*
G36*
G01X868092Y1540276D02*
X865225D01*
G02X865179Y1544708I-1387J2202D01*
G01X865226Y1544680D01*
X866163D01*
X866215Y1544715D01*
G02X868629Y1540802I1309J-1894D01*
G01X868604Y1540788D01*
X868092Y1540276D01*
G37*
G36*
G01X791697Y1541048D02*
G03X791497Y1541248I-200J0D01*
G02X789995Y1541807I2J2302D01*
G03X789717Y1541791I-131J-151D01*
G02Y1545309I-1918J1759D01*
G03X789995Y1545293I147J135D01*
G02X793801Y1543552I1504J-1743D01*
G03X794001Y1543352I200J0D01*
G02X795503Y1542793I-2J-2302D01*
G03X795781Y1542809I131J151D01*
G02Y1539291I1918J-1759D01*
G03X795503Y1539307I-147J-135D01*
G02X791697Y1541048I-1504J1743D01*
G37*
G36*
G01X868639Y1533354D02*
X868616Y1533336D01*
X867347Y1531523D01*
X867339Y1531485D01*
G02X864030Y1534536I-2540J565D01*
G01X864096Y1534556D01*
X865009Y1535861D01*
X865019Y1535888D01*
G02X868639Y1533354I2180J-738D01*
G37*
G36*
G01X772799Y1535258D02*
G03X772776Y1535536I-155J127D01*
G02X776292Y1535620I1712J1959D01*
G03X776283Y1535342I139J-144D01*
G02X776221Y1532185I-1706J-1546D01*
G03X776216Y1531630I286J-280D01*
G02X776285Y1528546I-1674J-1580D01*
G03X776301Y1528268I151J-131D01*
G02X772783I-1759J-1918D01*
G03X772799Y1528546I-135J147D01*
G02X772898Y1531661I1743J1504D01*
G03X772903Y1532216I-286J280D01*
G02X772799Y1535258I1674J1580D01*
G37*
G36*
G01X280712Y1528452D02*
G03X280779Y1527923I329J-227D01*
G02X276930Y1527430I-1704J-1966D01*
G03X276863Y1527959I-329J227D01*
G02X280712Y1528452I1704J1966D01*
G37*
G36*
G01X752940Y1519266D02*
G03Y1518734I299J-266D01*
G02X749060I-1940J-1734D01*
G03Y1519266I-299J266D01*
G02Y1522734I1940J1734D01*
G03Y1523266I-299J266D01*
G02X752940I1940J1734D01*
G03Y1522734I299J-266D01*
G02Y1519266I-1940J-1734D01*
G37*
G36*
G01X392688Y1516234D02*
G03Y1515962I147J-136D01*
G02X389310I-1689J-1564D01*
G03Y1516234I-147J136D01*
G02X392688I1689J1564D01*
G37*
G36*
G01X292976Y1546899D02*
G02X291832Y1544282I-2565J-437D01*
G01Y1530199D01*
X279891Y1518258D01*
G03X280084Y1517585I283J-283D01*
G02X281222Y1513100I-585J-2535D01*
G03Y1512500I264J-300D01*
G02X277776I-1723J-1950D01*
G03Y1513100I-264J300D01*
G02X276964Y1514465I1723J1949D01*
G03X276291Y1514658I-390J-90D01*
G01X275412Y1513780D01*
X269884D01*
G03X269500Y1513269I0J-400D01*
G02X264498I-2501J-719D01*
G03X264114Y1513780I-384J111D01*
G01X262379D01*
X262363Y1513777D01*
G02X264189Y1516759I-364J2273D01*
G01X264234Y1516620D01*
X264568D01*
G03X264938Y1517171I-1J400D01*
G02X265579Y1520057I2411J979D01*
G03Y1520643I-273J293D01*
G02X265688Y1524553I1770J1907D01*
G03Y1525169I-255J308D01*
G02X269010I1661J2003D01*
G03Y1524553I255J-308D01*
G02X269119Y1520643I-1661J-2003D01*
G03Y1520057I273J-293D01*
G02X269760Y1517171I-1770J-1907D01*
G03X270130Y1516620I371J-151D01*
G01X274236D01*
X288990Y1531375D01*
Y1544282D01*
G02X290848Y1549027I1421J2180D01*
G01X290950Y1549010D01*
X309078Y1567138D01*
Y1567818D01*
G02X308859Y1567965I1171J1982D01*
G03X308268Y1567842I-242J-318D01*
G02X307753Y1571035I-2270J1272D01*
G03X308352Y1571104I269J296D01*
G02X311920Y1568216I1897J-1305D01*
G01Y1565962D01*
X292959Y1547001D01*
X292976Y1546899D01*
G37*
G36*
G01X797439Y1507383D02*
G03Y1506717I222J-333D01*
G02X794559I-1440J-2167D01*
G03Y1507383I-222J333D01*
G02X794276Y1511500I1440J2167D01*
G03Y1512100I-264J300D01*
G02Y1516000I1723J1950D01*
G03Y1516600I-264J300D01*
G02X797722I1723J1950D01*
G03Y1516000I264J-300D01*
G02Y1512100I-1723J-1950D01*
G03Y1511500I264J-300D01*
G02X797439Y1507383I-1723J-1950D01*
G37*
G36*
G01X807805Y1505889D02*
G03Y1506555I-222J333D01*
G02X807597Y1510736I1440J2167D01*
G03X807565Y1511379I-253J310D01*
G02X807790Y1515854I1434J2171D01*
G03X807823Y1516543I-186J354D01*
G02X810454Y1516418I1422J2179D01*
G03X810421Y1515729I186J-354D01*
G02X810647Y1511536I-1422J-2179D01*
G03X810679Y1510893I253J-310D01*
G02X810685Y1506555I-1434J-2171D01*
G03Y1505889I222J-333D01*
G02X807805I-1440J-2167D01*
G37*
G36*
G01X865718Y1502356D02*
X865732Y1502331D01*
X866966Y1501097D01*
X867025Y1501085D01*
G02X864027Y1497776I-509J-2552D01*
G01X864012Y1497824D01*
X862618Y1499217D01*
X862593Y1499231D01*
G02X865718Y1502356I1106J2019D01*
G37*
G36*
G01X258735Y1505814D02*
G02X263263Y1501286I2264J-2264D01*
G01X196200Y1434224D01*
Y1388528D01*
G02X194700Y1382498I-1500J-2828D01*
G01X194151D01*
G02X191887Y1383436I0J3201D01*
G01X189798Y1385526D01*
Y1436876D01*
X232204Y1479283D01*
G03X232185Y1479867I-282J283D01*
G02X235433Y1483115I1515J1733D01*
G03X236017Y1483096I301J263D01*
G01X258735Y1505814D01*
G37*
G36*
G01X183210Y1364854D02*
X183202Y1364827D01*
Y1362387D01*
G02X178798I-2202J-1387D01*
G01Y1364827D01*
X178790Y1364854D01*
G02X179476Y1367225I2210J645D01*
G03X179402Y1367877I-265J300D01*
G02X178481Y1368794I1098J2023D01*
G01X178467Y1368819D01*
X178198Y1369088D01*
Y1369854D01*
G02Y1369946I2302J46D01*
G01Y1372613D01*
G02X182602I2202J1387D01*
G01Y1370840D01*
G02X182024Y1368175I-2102J-939D01*
G03X182098Y1367523I265J-300D01*
G02X183210Y1364854I-1098J-2024D01*
G37*
G36*
G01X261233Y1163490D02*
G03X261765I266J299D01*
G02X265449Y1163273I1734J-1940D01*
G03X266049I300J264D01*
G02X269733Y1163490I1950J-1723D01*
G03X270265I266J299D01*
G02Y1159610I1734J-1940D01*
G03X269733I-266J-299D01*
G02X266049Y1159827I-1734J1940D01*
G03X265449I-300J-264D01*
G02X261765Y1159610I-1950J1723D01*
G03X261233I-266J-299D01*
G02Y1163490I-1734J1940D01*
G37*
G36*
G01X785056Y1159942D02*
G03Y1159342I264J-300D01*
G02X781610I-1723J-1950D01*
G03Y1159942I-264J300D01*
G02X780880Y1162761I1723J1950D01*
G03X780481Y1163294I-377J134D01*
G02X778383Y1164169I-148J2598D01*
G03X777783I-300J-264D01*
G02X773883I-1950J1723D01*
G03X773283I-300J-264D01*
G02X773273Y1164158I-1930J1745D01*
G03Y1163626I299J-266D01*
G02X769393I-1940J-1734D01*
G03Y1164158I-299J266D01*
G02X773283Y1167615I1940J1734D01*
G03X773883I300J264D01*
G02X777783I1950J-1723D01*
G03X778383I300J264D01*
G02X782786Y1165023I1950J-1723D01*
G03X783185Y1164490I377J-134D01*
G02X785056Y1159942I148J-2598D01*
G37*
G36*
G01X262294Y1151085D02*
G03X261761Y1151077I-262J-302D01*
G02X261704Y1154957I-1762J1915D01*
G03X262237Y1154965I262J302D01*
G02X265949Y1154773I1762J-1915D01*
G03X266549I300J264D01*
G02X270233Y1154990I1950J-1723D01*
G03X270765I266J299D01*
G02Y1151110I1734J-1940D01*
G03X270233I-266J-299D01*
G02X266549Y1151327I-1734J1940D01*
G03X265949I-300J-264D01*
G02X262294Y1151085I-1950J1723D01*
G37*
G36*
G01X803872Y1154052D02*
X805512D01*
G02Y1149648I1387J-2202D01*
G01X803872D01*
X803845Y1149640D01*
G02Y1154060I-646J2210D01*
G01X803872Y1154052D01*
G37*
G36*
G01X789878Y1135584D02*
G03X789665Y1135754I-198J-30D01*
G02X787415Y1139027I-166J2296D01*
G01X787434Y1139067D01*
Y1140446D01*
G02X790588Y1140686I1420J2180D01*
G03X790654Y1140041I266J-299D01*
G02X791775Y1138392I-1155J-1991D01*
G03X791988Y1138222I198J30D01*
G02X793658Y1137669I166J-2296D01*
G03X793936Y1137685I131J151D01*
G02Y1134167I1918J-1759D01*
G03X793658Y1134183I-147J-135D01*
G02X789878Y1135584I-1504J1743D01*
G37*
G36*
G01X775275Y1130791D02*
X775233Y1130775D01*
X774786Y1130328D01*
X774793Y1130236D01*
G02X771765Y1132232I-2294J-186D01*
G03X771893Y1132480I-63J190D01*
G02X775275Y1130791I2490J755D01*
G37*
G36*
G01X780196Y1128344D02*
X779777Y1128763D01*
X779685Y1128756D01*
G02X781686Y1131770I-186J2294D01*
G03X781932Y1131641I190J63D01*
G02X780211Y1128300I740J-2495D01*
G01X780196Y1128344D01*
G37*
G36*
G01X865172Y1130952D02*
X867363D01*
G02Y1126548I1387J-2202D01*
G01X865172D01*
X865145Y1126540D01*
G02Y1130960I-646J2210D01*
G01X865172Y1130952D01*
G37*
G36*
G01X770605Y1122718D02*
G03X770329Y1122684I-120J-159D01*
G02X770111Y1126195I-2023J1637D01*
G03X770390Y1126196I139J144D01*
G02X770605Y1122718I1609J-1646D01*
G37*
G36*
G01X800765Y1095626D02*
G03X800233I-266J-299D01*
G02Y1099506I-1734J1940D01*
G03X800765I266J299D01*
G02X804812Y1098758I1734J-1940D01*
G03X805478Y1098689I356J183D01*
G02X805559Y1098785I2029J-1630D01*
G03X805538Y1099340I-298J267D01*
G02X805661Y1103203I1803J1876D01*
G03X805615Y1103847I-259J305D01*
G02X805833Y1108376I1384J2203D01*
G03X805878Y1109064I-180J357D01*
G02X805901Y1113383I1463J2152D01*
G03Y1114049I-222J333D01*
G02X808781I1440J2167D01*
G03Y1113383I222J-333D01*
G02X808507Y1108890I-1440J-2167D01*
G03X808462Y1108202I180J-357D01*
G02X808679Y1104063I-1463J-2152D01*
G03X808725Y1103419I259J-305D01*
G02X809281Y1099481I-1384J-2204D01*
G03X809302Y1098926I298J-267D01*
G02X809356Y1098872I-1812J-1867D01*
G03X809642I143J140D01*
G02X809765Y1095110I1857J-1822D01*
G03X809233I-266J-299D01*
G02X805186Y1095858I-1734J1940D01*
G03X804520Y1095927I-356J-183D01*
G02X800765Y1095626I-2021J1639D01*
G37*
G36*
G01X817602Y1081113D02*
Y1079473D01*
X817610Y1079446D01*
G02X813190I-2210J-646D01*
G01X813198Y1079473D01*
Y1081113D01*
G02X817602I2202J1387D01*
G37*
G36*
G01X227598Y1075913D02*
G02X232001I2201J1387D01*
G01Y1074273D01*
X232010Y1074246D01*
G02X227590I-2210J-646D01*
G01X227598Y1074273D01*
Y1075913D01*
G37*
G36*
G01X827702Y1074913D02*
Y1073597D01*
G02X823781Y1071194I-1902J-1296D01*
G01X823767Y1071219D01*
X823298Y1071688D01*
Y1074913D01*
G02X827702I2202J1387D01*
G37*
G36*
G01X239798Y1068313D02*
G02X244201I2202J1387D01*
G01Y1066673D01*
X244210Y1066646D01*
G02X239790I-2210J-646D01*
G01X239798Y1066673D01*
Y1068313D01*
G37*
G36*
G01X216949Y950336D02*
G03X217549I300J264D01*
G02X221062Y946533I1950J-1723D01*
G03Y945893I240J-320D01*
G02X221358Y941993I-1563J-2080D01*
G03Y941433I286J-280D01*
G02X217549Y937890I-1859J-1820D01*
G03X216949I-300J-264D01*
G02X213276Y941563I-1950J1723D01*
G03Y942163I-264J300D01*
G02Y946063I1723J1950D01*
G03Y946663I-264J300D01*
G02X216949Y950336I1723J1950D01*
G37*
G36*
G01Y928336D02*
G03X217549I300J264D01*
G02Y924890I1950J-1723D01*
G03X216949I-300J-264D01*
G02Y928336I-1950J1723D01*
G37*
G36*
G01X212152Y892190D02*
X212028Y892313D01*
X211936Y892306D01*
G02X213619Y895944I-186J2294D01*
G03X214151Y895835I325J233D01*
G02X213320Y892190I1349J-2225D01*
G01X212152D01*
G37*
G36*
G01X213802Y885523D02*
G03X213869Y886056I-260J303D01*
G02X217949Y889273I2130J1494D01*
G03X218549I300J264D01*
G02Y885827I1950J-1723D01*
G03X217949I-300J-264D01*
G02X217696Y885577I-1951J1722D01*
G03X217629Y885044I260J-303D01*
G02X213802Y885523I-2130J-1494D01*
G37*
G36*
G01X202644Y843771D02*
G03X202624Y844304I-308J255D01*
G02X206447Y847832I1872J1807D01*
G03X207047Y847833I300J265D01*
G02X210934Y844373I1953J-1720D01*
G03X210932Y843840I298J-268D01*
G02X210907Y840358I-1946J-1727D01*
G03X210909Y839817I296J-269D01*
G02X207114Y836257I-1910J-1767D01*
G03X206534I-290J-276D01*
G02X202733Y839811I-1885J1793D01*
G03Y840352I-294J271D01*
G02X202644Y843771I1916J1761D01*
G37*
G36*
G01X293265Y756110D02*
G03X292733I-266J-299D01*
G02X289276Y760000I-1734J1940D01*
G03Y760600I-264J300D01*
G02Y764500I1723J1950D01*
G03Y765100I-264J300D01*
G02X292733Y768990I1723J1950D01*
G03X293265I266J299D01*
G02X296722Y765100I1734J-1940D01*
G03Y764500I264J-300D01*
G02Y760600I-1723J-1950D01*
G03Y760000I264J-300D01*
G02X293265Y756110I-1723J-1950D01*
G37*
G36*
G01X801586Y760048D02*
Y758824D01*
X801615Y758777D01*
G02X797155I-2230J-1341D01*
G01X797184Y758824D01*
Y760048D01*
X797155Y760095D01*
G02X801615I2230J1341D01*
G01X801586Y760048D01*
G37*
G36*
G01X784919Y758432D02*
G03Y757832I264J-300D01*
G02X781473I-1723J-1950D01*
G03Y758432I-264J300D01*
G02X780743Y761251I1723J1950D01*
G03X780344Y761784I-377J134D01*
G02X778246Y762659I-148J2598D01*
G03X777646I-300J-264D01*
G02X773746I-1950J1723D01*
G03X773146I-300J-264D01*
G02X773136Y762648I-1930J1745D01*
G03Y762116I299J-266D01*
G02X769256I-1940J-1734D01*
G03Y762648I-299J266D01*
G02X773146Y766105I1940J1734D01*
G03X773746I300J264D01*
G02X777646I1950J-1723D01*
G03X778246I300J264D01*
G02X782649Y763513I1950J-1723D01*
G03X783048Y762980I377J-134D01*
G02X784919Y758432I148J-2598D01*
G37*
G36*
G01X330826Y739729D02*
X330724Y739746D01*
X330107Y739130D01*
X329813D01*
X329753Y739059D01*
G02X326247Y742043I-1754J1491D01*
G03X326227Y742323I-152J130D01*
G02X329865Y744956I1522J1727D01*
G03X330370Y744738I368J158D01*
G02X330826Y739729I893J-2444D01*
G37*
G36*
G01X771813Y734470D02*
X772017D01*
X772076Y734555D01*
G02Y731545I2123J-1505D01*
G01X772017Y731630D01*
X771813D01*
X771753Y731559D01*
G02Y734541I-1754J1491D01*
G01X771813Y734470D01*
G37*
G36*
G01X786812Y735330D02*
G03X786566Y735459I-190J-63D01*
G02X788287Y738800I-740J2495D01*
G01X788302Y738756D01*
X788721Y738337D01*
X788813Y738344D01*
G02X791285Y735780I186J-2294D01*
G03X791729Y735336I397J-47D01*
G02X793742Y731546I270J-2286D01*
G03X793758Y731268I151J-131D01*
G02X790240I-1759J-1918D01*
G03X790256Y731546I-135J147D01*
G02X789713Y733320I1743J1504D01*
G03X789269Y733764I-397J47D01*
G02X786812Y735330I-270J2286D01*
G37*
G36*
G01X869111Y722348D02*
X867887D01*
X867840Y722320D01*
G02Y726780I-1341J2230D01*
G01X867887Y726752D01*
X869111D01*
X869158Y726780D01*
G02Y722320I1341J-2230D01*
G01X869111Y722348D01*
G37*
G36*
G01X772822Y724894D02*
G03X772807Y724339I281J-285D01*
G02X769323Y724246I-1702J-1550D01*
G03X769278Y724799I-310J253D01*
G02X772822Y724894I1721J1951D01*
G37*
G36*
G01X747737Y714135D02*
G03X747138Y714068I-270J-295D01*
G02X743517Y717689I-2139J1482D01*
G03X743584Y718288I-228J329D01*
G02X747449Y721773I1915J1762D01*
G03X748049I300J264D01*
G02X751696Y718077I1949J-1724D01*
G03X751629Y717544I260J-303D01*
G02X747737Y714135I-2130J-1494D01*
G37*
G36*
G01X282675Y715559D02*
G03X282599Y715032I257J-306D01*
G02X278757Y715581I-2166J-1442D01*
G03X278833Y716108I-257J306D01*
G02X282675Y715559I2166J1442D01*
G37*
G36*
G01X282939Y703816D02*
G03Y703284I299J-266D01*
G02X279059I-1940J-1734D01*
G03Y703816I-299J266D01*
G02X282939I1940J1734D01*
G37*
G36*
G01X796054Y700903D02*
G03Y700303I264J-300D01*
G02X792608I-1723J-1950D01*
G03Y700903I-264J300D01*
G02Y704803I1723J1950D01*
G03Y705403I-264J300D01*
G02Y709303I1723J1950D01*
G03Y709903I-264J300D01*
G02X796054I1723J1950D01*
G03Y709303I264J-300D01*
G02Y705403I-1723J-1950D01*
G03Y704803I264J-300D01*
G02Y700903I-1723J-1950D01*
G37*
G36*
G01X287128Y747235D02*
G03X287131Y746673I286J-279D01*
G02X287616Y745953I-1632J-1623D01*
G03X288267Y745827I368J157D01*
G01X297411Y754970D01*
X304689D01*
G02X305229Y755469I1812J-1419D01*
G03X305274Y756102I-221J334D01*
G02X308256Y755772I1725J1948D01*
G03X308160Y755144I193J-351D01*
G02X304689Y752130I-1660J-1594D01*
G01X298587D01*
X286608Y740150D01*
G02X284327Y735750I-1844J-1835D01*
G01X284225Y735767D01*
X280027Y731569D01*
G03X280255Y730890I283J-283D01*
G02X277659Y728294I-316J-2280D01*
G03X276980Y728522I-396J-55D01*
G01X268292Y719834D01*
G03X268564Y719151I283J-283D01*
G02X269939Y714383I-65J-2601D01*
G03Y713717I222J-333D01*
G02Y709383I-1440J-2167D01*
G03Y708717I222J-333D01*
G02Y704383I-1440J-2167D01*
G03Y703717I222J-333D01*
G02X267059I-1440J-2167D01*
G03Y704383I-222J333D01*
G02Y708717I1440J2167D01*
G03Y709383I-222J333D01*
G02Y713717I1440J2167D01*
G03Y714383I-222J333D01*
G02X265898Y716485I1440J2167D01*
G03X265215Y716757I-400J-11D01*
G01X255920Y707462D01*
Y699511D01*
G02X253078I-1421J-1811D01*
G01Y708638D01*
X282216Y737776D01*
X282199Y737878D01*
G02X283344Y740495I2565J437D01*
G01Y740903D01*
X284722Y742282D01*
G03X284596Y742933I-283J283D01*
G02X283935Y743361I902J2118D01*
G03X283663I-136J-147D01*
G02X282507Y747316I-1564J1689D01*
G03X282936Y747888I71J393D01*
G02X287128Y747235I2328J1162D01*
G37*
G36*
G01X808462Y699826D02*
G03X808485Y699186I251J-311D01*
G02X805368Y699077I-1486J-2136D01*
G03X805345Y699717I-251J311D01*
G02X805391Y704020I1486J2136D01*
G03Y704686I-222J333D01*
G02Y709020I1440J2167D01*
G03Y709686I-222J333D01*
G02X808271I1440J2167D01*
G03Y709020I222J-333D01*
G02Y704686I-1440J-2167D01*
G03Y704020I222J-333D01*
G02X808462Y699826I-1440J-2167D01*
G37*
G36*
G01X815002Y678512D02*
Y677333D01*
G02X811323Y674568I-1801J-1433D01*
G02X810598Y676200I1477J1633D01*
G01Y678513D01*
G02X815030Y678559I2202J1387D01*
G01X815002Y678512D01*
G37*
G36*
G01X823102Y663688D02*
X822632Y663219D01*
G02X818666Y665549I-2032J1081D01*
G01X818698Y665599D01*
Y666612D01*
X818670Y666659D01*
G02X823102Y666613I2230J1341D01*
G01Y663688D01*
G37*
G36*
G01X146550Y649141D02*
Y645268D01*
X146543Y645180D01*
G02X141926Y645356I-2305J176D01*
G01Y649131D01*
G02X146550Y649141I2312J0D01*
G37*
G36*
G01X127810Y638960D02*
Y635462D01*
X127804Y635374D01*
G02X123188Y635550I-2305J176D01*
G01Y638950D01*
G02X127810Y638960I2311J0D01*
G37*
G36*
G01X556774Y614102D02*
G03X556215Y614074I-265J-299D01*
G02X552537Y617750I-1911J1766D01*
G03X552563Y618311I-271J294D01*
G02X552776Y622000I1936J1739D01*
G03Y622600I-264J300D01*
G02X556319Y626409I1723J1950D01*
G03X556879I280J286D01*
G02X560517Y622689I1820J-1859D01*
G03X560518Y622115I279J-287D01*
G02X560475Y618334I-1809J-1870D01*
G03X560447Y617775I271J-294D01*
G02X556774Y614102I-1948J-1725D01*
G37*
G36*
G01X154387Y576202D02*
X157217D01*
X157376Y576122D01*
X157404Y576117D01*
G02X158379Y575694I-404J-2266D01*
G01X158432Y575655D01*
X158698D01*
Y576115D01*
X158684Y576151D01*
G02X163103Y576679I2140J849D01*
G01X163102Y576665D01*
Y574387D01*
G02X158653Y571688I-2202J-1387D01*
G03X158114Y571836I-345J-202D01*
G02X155958Y571798I-1114J2015D01*
G01X154387D01*
G02Y576202I-1387J2202D01*
G37*
G36*
G01X139652Y571009D02*
X139664Y570950D01*
X143502Y567112D01*
Y566573D01*
X143510Y566546D01*
G02X142633Y564023I-2210J-646D01*
G03X142579Y563416I231J-326D01*
G02X139607Y563677I-1639J-1616D01*
G03X139661Y564284I-231J326D01*
G02X139088Y565264I1639J1616D01*
G01X139073Y565313D01*
X136391Y567996D01*
X136343Y568011D01*
G02X139652Y571009I757J2489D01*
G37*
G36*
G01X137117Y551598D02*
X136088D01*
X136041Y551570D01*
G02X136087Y556002I-1341J2230D01*
G01X139028D01*
X139497Y555533D01*
X139522Y555519D01*
G02X137167Y551566I-1106J-2019D01*
G01X137117Y551598D01*
G37*
G36*
G01X62310Y537547D02*
X62315Y534063D01*
X62308Y533974D01*
G02X57692Y534147I-2305J177D01*
G01X57688Y537547D01*
X57687D01*
G02X62303Y537735I2312J3D01*
G01X62310Y537643D01*
Y537547D01*
G37*
G36*
G01X98900Y511088D02*
X95500D01*
G02Y515712I0J2312D01*
G01X98900D01*
G02X101212Y513410I0J-2312D01*
G01Y513312D01*
X101205Y513224D01*
G02X98900Y511088I-2305J176D01*
G37*
G36*
G01X134961Y506848D02*
X133737D01*
X133690Y506820D01*
G02Y511280I-1341J2230D01*
G01X133737Y511252D01*
X134961D01*
X135008Y511280D01*
G02Y506820I1341J-2230D01*
G01X134961Y506848D01*
G37*
G36*
G01X144283Y423048D02*
G03X143777Y422721I-110J-384D01*
G02X140224Y424967I-2278J329D01*
G03Y425633I-221J333D01*
G02X143253Y429041I1275J1917D01*
G01X143313Y428970D01*
X143587D01*
X144460Y428098D01*
X144562Y428115D01*
G02X144283Y423048I437J-2565D01*
G37*
G36*
G01X786201Y357974D02*
G03Y357374I264J-300D01*
G02X782755I-1723J-1950D01*
G03Y357974I-264J300D01*
G02X782025Y360793I1723J1950D01*
G03X781626Y361326I-377J134D01*
G02X779528Y362201I-148J2598D01*
G03X778928I-300J-264D01*
G02X775028I-1950J1723D01*
G03X774428I-300J-264D01*
G02X774418Y362190I-1930J1745D01*
G03Y361658I299J-266D01*
G02X770538I-1940J-1734D01*
G03Y362190I-299J266D01*
G02X774428Y365647I1940J1734D01*
G03X775028I300J264D01*
G02X778928I1950J-1723D01*
G03X779528I300J264D01*
G02X783931Y363055I1950J-1723D01*
G03X784330Y362522I377J-134D01*
G02X786201Y357974I148J-2598D01*
G37*
G36*
G01X292264Y350174D02*
G03X291732I-266J-299D01*
G02X288275Y354064I-1734J1940D01*
G03Y354664I-264J300D01*
G02Y358564I1723J1950D01*
G03Y359164I-264J300D01*
G02X291732Y363054I1723J1950D01*
G03X292264I266J299D01*
G02X295721Y359164I1734J-1940D01*
G03Y358564I264J-300D01*
G02Y354664I-1723J-1950D01*
G03Y354064I264J-300D01*
G02X292264Y350174I-1723J-1950D01*
G37*
G36*
G01X868972Y338352D02*
X871101D01*
G02X871337Y333948I1498J-2128D01*
G01X868972D01*
X868945Y333940D01*
G02Y338360I-646J2210D01*
G01X868972Y338352D01*
G37*
G36*
G01X793003Y334793D02*
G03X793281Y334809I131J151D01*
G02Y331291I1918J-1759D01*
G03X793003Y331307I-147J-135D01*
G02X789359Y333898I-1504J1743D01*
G03X789137Y334416I-372J147D01*
G02X788256Y338054I862J2134D01*
G03X788240Y338332I-151J131D01*
G02X791758I1759J1918D01*
G03X791742Y338054I135J-147D01*
G02X792139Y335702I-1743J-1504D01*
G03X792361Y335184I372J-147D01*
G02X793003Y334793I-860J-2135D01*
G37*
G36*
G01X326495Y331752D02*
G03X326095Y331378I-1J-400D01*
G02X323936Y334115I-2596J172D01*
G01X324038Y334098D01*
X324206Y334266D01*
X324214Y334334D01*
G02X324810Y335618I2285J-280D01*
G03Y335890I-147J136D01*
G02X328188I1689J1564D01*
G03Y335618I147J-136D01*
G02X326495Y331752I-1689J-1564D01*
G37*
G36*
G01X775017Y326086D02*
G03X775498Y325556I373J-145D01*
G02X774281Y321291I701J-2506D01*
G03X774003Y321307I-147J-135D01*
G02X771069Y324854I-1504J1743D01*
G03X771124Y325427I-249J313D01*
G02X771130Y328428I1749J1497D01*
G03X771114Y328706I-151J131D01*
G02X774632I1759J1918D01*
G03X774616Y328428I135J-147D01*
G02X775017Y326086I-1743J-1504D01*
G37*
G36*
G01X559939Y324816D02*
G03Y324284I299J-266D01*
G02X556059I-1940J-1734D01*
G03Y324816I-299J266D01*
G02X556229Y328457I1940J1734D01*
G03X556220Y329051I-272J293D01*
G02X556083Y332840I1713J1959D01*
G03X556105Y333378I-284J281D01*
G02X559949Y333220I1994J1672D01*
G03X559927Y332682I284J-281D01*
G02X559703Y329103I-1994J-1672D01*
G03X559712Y328509I272J-293D01*
G02X559939Y324816I-1713J-1959D01*
G37*
G36*
G01X867226Y319348D02*
X865626D01*
G02X865544Y323752I-1427J2176D01*
G01X867226D01*
X867253Y323760D01*
G02Y319340I646J-2210D01*
G01X867226Y319348D01*
G37*
G36*
G01X281721Y297664D02*
G03Y297064I264J-300D01*
G02X278275I-1723J-1950D01*
G03Y297664I-264J300D01*
G02Y301564I1723J1950D01*
G03Y302164I-264J300D01*
G02Y306064I1723J1950D01*
G03Y306664I-264J300D01*
G02X281721I1723J1950D01*
G03Y306064I264J-300D01*
G02Y302164I-1723J-1950D01*
G03Y301564I264J-300D01*
G02Y297664I-1723J-1950D01*
G37*
G36*
G01X869472Y296952D02*
X871836D01*
G02X871430Y292548I1163J-2328D01*
G01X869472D01*
X869445Y292540D01*
G02Y296960I-646J2210D01*
G01X869472Y296952D01*
G37*
G36*
G01X798596Y296621D02*
G03Y296021I264J-300D01*
G02X795150I-1723J-1950D01*
G03Y296621I-264J300D01*
G02Y300521I1723J1950D01*
G03Y301121I-264J300D01*
G02Y305021I1723J1950D01*
G03Y305621I-264J300D01*
G02X798596I1723J1950D01*
G03Y305021I264J-300D01*
G02Y301121I-1723J-1950D01*
G03Y300521I264J-300D01*
G02Y296621I-1723J-1950D01*
G37*
G36*
G01X866172Y290252D02*
X867901D01*
G02X868137Y285848I1498J-2128D01*
G01X866172D01*
X866145Y285840D01*
G02Y290260I-646J2210D01*
G01X866172Y290252D01*
G37*
G36*
G01X822773Y281702D02*
X840163D01*
X840466Y282005D01*
X840480Y282030D01*
G02X843605Y278905I2019J-1106D01*
G01X843580Y278891D01*
X841987Y277298D01*
X822773D01*
X822746Y277290D01*
G02X821454I-646J2210D01*
G01X821427Y277298D01*
X772137D01*
X749338Y300098D01*
Y312597D01*
G02X749607Y315727I2201J1387D01*
G03X749602Y316269I-297J268D01*
G02X752633Y320392I1897J1781D01*
G03X753146Y320538I175J360D01*
G02X757083Y317211I2200J-1390D01*
G03X757103Y316599I267J-298D01*
G02X754321Y312230I-1604J-2049D01*
G03X753740Y311873I-181J-357D01*
G01Y301922D01*
X773961Y281702D01*
X821427D01*
X821454Y281710D01*
G02X822746I646J-2210D01*
G01X822773Y281702D01*
G37*
G36*
G01X818702Y273162D02*
Y271988D01*
X818730Y271941D01*
G02X814298Y271987I-2230J-1341D01*
G01Y275012D01*
X814667Y275381D01*
X814681Y275406D01*
G02X818726Y273206I2019J-1106D01*
G01X818702Y273162D01*
G37*
G36*
G01X824402Y261652D02*
Y259387D01*
G02X819998I-2202J-1387D01*
G01Y260759D01*
X819982Y260797D01*
G02X824119Y262806I2118J903D01*
G01X824133Y262781D01*
X824402Y262512D01*
Y261746D01*
G02Y261654I-2302J-46D01*
G01Y261652D01*
G37*
G36*
G01X831817Y217500D02*
G03X832359Y217386I330J225D01*
G02X831676Y214132I1217J-1954D01*
G03X831134Y214246I-330J-225D01*
G02X831817Y217500I-1217J1954D01*
G37*
G36*
G01X156232Y169581D02*
X157392Y168421D01*
X157446Y168408D01*
G02X154292Y165254I-629J-2525D01*
G01X154279Y165308D01*
X153119Y166468D01*
G02X156232Y169581I1081J2032D01*
G37*
G36*
G01X151602Y165727D02*
Y163887D01*
G02X147198I-2202J-1387D01*
G01Y165727D01*
X147190Y165754D01*
G02X151610I2210J646D01*
G01X151602Y165727D01*
G37*
G36*
G01X869080Y162249D02*
G03X869091Y161657I274J-291D01*
G02X865996Y161599I-1516J-1733D01*
G03X865985Y162191I-274J291D01*
G02X869080Y162249I1516J1733D01*
G37*
G36*
G01X756265Y152610D02*
G03X755733I-266J-299D01*
G02X752276Y156500I-1734J1940D01*
G03Y157100I-264J300D01*
G02X755733Y160990I1723J1950D01*
G03X756265I266J299D01*
G02X759722Y157100I1734J-1940D01*
G03Y156500I264J-300D01*
G02X756265Y152610I-1723J-1950D01*
G37*
G36*
G01X318002Y102813D02*
Y101173D01*
X318010Y101146D01*
G02X313590I-2210J-646D01*
G01X313598Y101173D01*
Y102813D01*
G02X318002I2202J1387D01*
G37*
G36*
G01X373048Y97348D02*
X343001D01*
X270001Y170348D01*
X221001D01*
X219798Y171552D01*
Y188002D01*
G03X219265Y188379I-400J0D01*
G02Y192721I-766J2171D01*
G03X219798Y193098I133J377D01*
G01Y205497D01*
X221502Y207202D01*
X286998D01*
X375702Y118498D01*
Y100002D01*
X373048Y97348D01*
G37*
G36*
G01X76188Y82486D02*
G03Y82214I147J-136D01*
G02X72810I-1689J-1564D01*
G03Y82486I-147J136D01*
G02X76188I1689J1564D01*
G37*
G36*
G01X311111Y70348D02*
X309887D01*
X309840Y70320D01*
G02X306044Y71687I-1341J2230D01*
G03X305445Y71887I-377J-133D01*
G02X306454Y74913I-1446J2163D01*
G03X307053Y74713I377J133D01*
G02X309840Y74780I1446J-2163D01*
G01X309887Y74752D01*
X311111D01*
X311158Y74780D01*
G02Y70320I1341J-2230D01*
G01X311111Y70348D01*
G37*
G36*
G01X354326Y69848D02*
X347587D01*
X334662Y82774D01*
X310162D01*
X307918Y85017D01*
X307893Y85031D01*
G02X311018Y88156I1106J2019D01*
G01X311032Y88131D01*
X311986Y87176D01*
X322806D01*
G03X323101Y87846I0J400D01*
G02X322590Y90046I1699J1554D01*
G01X322598Y90073D01*
Y91713D01*
G02X327002I2202J1387D01*
G01Y90073D01*
X327010Y90046D01*
G02X326499Y87846I-2210J-646D01*
G03X326794Y87176I295J-270D01*
G01X336486D01*
X349411Y74252D01*
X354326D01*
X354353Y74260D01*
G02Y69840I646J-2210D01*
G01X354326Y69848D01*
G37*
G36*
G01X77191Y68961D02*
G03X76643Y68939I-262J-302D01*
G02X73354Y72160I-1644J1611D01*
G03Y72440I-143J140D01*
G02X76508Y75789I1645J1611D01*
G03X77056Y75811I262J302D01*
G02X80345Y72590I1644J-1611D01*
G03Y72310I143J-140D01*
G02X77191Y68961I-1645J-1611D01*
G37*
G36*
G01X289219Y69448D02*
G03X289085Y70114I-274J291D01*
G02X288658Y70320I912J2437D01*
G01X288611Y70348D01*
X287387D01*
X287340Y70320D01*
G02X285717Y75137I-1341J2230D01*
G03X286050Y75670I-43J397D01*
G02X287097Y78742I2449J880D01*
G03X287231Y79275I-215J337D01*
G02X290901Y78358I2268J1275D01*
G03X290767Y77825I215J-337D01*
G02X290861Y75458I-2268J-1275D01*
G03X291061Y74925I363J-168D01*
G02X291779Y70652I-1062J-2375D01*
G03X291913Y69986I274J-291D01*
G02X289219Y69448I-914J-2436D01*
G37*
G36*
G01X379549Y63827D02*
G03X378949I-300J-264D01*
G02X375276Y67500I-1950J1723D01*
G03Y68100I-264J300D01*
G02X378949Y71773I1723J1950D01*
G03X379549I300J264D01*
G02X383222Y68100I1950J-1723D01*
G03Y67500I264J-300D01*
G02X379549Y63827I-1723J-1950D01*
G37*
G36*
G01X343018Y65380D02*
G03Y64780I264J-300D01*
G02X340153Y64918I-1519J-1730D01*
G03Y65242I-117J162D01*
G02X339995Y65367I1348J1866D01*
G03X339717Y65351I-131J-151D01*
G02Y68869I-1918J1759D01*
G03X339995Y68853I147J135D01*
G02X343018Y65380I1504J-1743D01*
G37*
G36*
G01X381990Y51248D02*
X381906D01*
X380866Y50208D01*
X380850Y50169D01*
G02X379211Y53600I-2422J950D01*
G03X379727Y53918I121J382D01*
G02X380354Y55160I2272J-368D01*
G03Y55440I-143J140D01*
G02X382427Y59312I1645J1610D01*
G03X382900Y59684I74J393D01*
G02X385062Y56985I2599J-134D01*
G01X384960Y57002D01*
X384126Y56168D01*
X384110Y56133D01*
G02X383644Y55440I-2111J917D01*
G03Y55160I143J-140D01*
G02X381990Y51248I-1645J-1610D01*
G37*
G36*
G01X95586Y52332D02*
G03X96119Y51999I397J43D01*
G02X94412Y49268I880J-2449D01*
G03X93879Y49601I-397J-43D01*
G02X95586Y52332I-880J2449D01*
G37*
G36*
G01X392778Y46861D02*
Y65262D01*
X390950Y67090D01*
X390848Y67073D01*
G02X387846Y70075I-437J2565D01*
G01X387863Y70177D01*
X373961Y84080D01*
X373514D01*
X373454Y84009D01*
G02X373511Y86920I-1754J1490D01*
G01X375137D01*
X389872Y72186D01*
X389974Y72203D01*
G02X392976Y69201I437J-2565D01*
G01X392959Y69099D01*
X395620Y66438D01*
Y46861D01*
G02X392778I-1421J-1811D01*
G37*
G36*
G01X91644Y41979D02*
G03X91657Y42671I-194J350D01*
G02X94256Y42621I1343J2229D01*
G03X94243Y41929I194J-350D01*
G02X94303Y41891I-1362J-2217D01*
G03X94836Y41985I215J337D01*
G02X98982Y38839I2064J-1585D01*
G03X99102Y38253I320J-240D01*
G02X95718Y37561I-1302J-2253D01*
G03X95598Y38147I-320J240D01*
G02X95497Y38209I1310J2248D01*
G03X94964Y38115I-215J-337D01*
G02X91644Y41979I-2064J1585D01*
G37*
G36*
G01X344505Y33720D02*
X345941D01*
G02Y29318I1387J-2201D01*
G01X342718D01*
X342418Y29617D01*
X342393Y29631D01*
G02X344505Y33720I1106J2019D01*
G37*
G36*
G01X291930Y39977D02*
G03X292587Y39837I374J143D01*
G01X303001Y50252D01*
X311497D01*
X313200Y48548D01*
Y32552D01*
X305847Y25198D01*
X290702D01*
X288298Y27603D01*
Y32219D01*
G03X287725Y32580I-400J0D01*
G02X286700Y37528I-1122J2348D01*
G03X287086Y38077I15J400D01*
G02X291930Y39977I2413J973D01*
G37*
G36*
G01X374549Y13827D02*
G03X373949I-300J-264D01*
G02X369458Y16110I-1950J1723D01*
G03X369192Y16576I-391J86D01*
G02X368276Y21000I807J2474D01*
G03Y21600I-264J300D01*
G02X371722I1723J1950D01*
G03Y21000I264J-300D01*
G02X372540Y18490I-1723J-1950D01*
G03X372806Y18024I391J-86D01*
G02X373949Y17273I-807J-2474D01*
G03X374549I300J264D01*
G02X378449I1950J-1723D01*
G03X379049I300J264D01*
G02X380136Y18005I1950J-1723D01*
G03X380336Y18604I-133J377D01*
G02X383362Y17595I2163J1446D01*
G03X383162Y16996I133J-377D01*
G02X379049Y13827I-2163J-1446D01*
G03X378449I-300J-264D01*
G02X374549I-1950J1723D01*
G37*
G36*
G01X255292Y293221D02*
G02X252450I-1421J-1811D01*
G01Y303010D01*
X277797Y328357D01*
X277780Y328459D01*
G02X280782Y331461I2565J437D01*
G01X280884Y331444D01*
X285111Y335671D01*
G03X284853Y336353I-283J283D01*
G02X283436Y336960I146J2297D01*
G03X283156Y336952I-136J-147D01*
G02X283062Y340240I-1657J1598D01*
G03X283342Y340248I136J147D01*
G02X283455Y340358I1661J-1594D01*
G03X283441Y340666I-134J148D01*
G02X286713Y340792I1558J2084D01*
G03X286684Y340219I264J-301D01*
G02X287296Y338796I-1685J-1568D01*
G03X287978Y338538I399J25D01*
G01X296911Y347470D01*
X299438D01*
G02Y344630I1811J-1420D01*
G01X298087D01*
X282893Y329435D01*
X282910Y329333D01*
G02X279908Y326331I-2565J-437D01*
G01X279806Y326348D01*
X266832Y313374D01*
G03X267166Y312695I283J-282D01*
G02X268938Y307947I332J-2581D01*
G03Y307281I222J-333D01*
G02Y302947I-1440J-2167D01*
G03Y302281I222J-333D01*
G02Y297947I-1440J-2167D01*
G03Y297281I222J-333D01*
G02X266058I-1440J-2167D01*
G03Y297947I-222J333D01*
G02Y302281I1440J2167D01*
G03Y302947I-222J333D01*
G02Y307281I1440J2167D01*
G03Y307947I-222J333D01*
G02X264917Y310446I1440J2167D01*
G03X264238Y310780I-397J51D01*
G01X255292Y301834D01*
Y293221D01*
G37*
G36*
G01X810813Y294738D02*
G02X807933I-1440J-2167D01*
G03Y295404I-222J333D01*
G02X808162Y299874I1440J2167D01*
G03X808112Y300604I-186J354D01*
G02X807462Y305150I887J2446D01*
G03X807512Y305752I-236J323D01*
G02X810910Y305471I1861J1819D01*
G03X810860Y304869I236J-323D01*
G02X810210Y300747I-1861J-1819D01*
G03X810260Y300017I186J-354D01*
G02X810813Y295404I-887J-2446D01*
G03Y294738I222J-333D01*
G37*
G36*
G01X189222Y533563D02*
G02X185776I-1723J-1950D01*
G03Y534163I-264J300D01*
G02X186918Y538649I1723J1950D01*
G03X187118Y539315I-89J390D01*
G02X187276Y543063I1881J1798D01*
G03Y543663I-264J300D01*
G02X187059Y547347I1723J1950D01*
G03Y547879I-299J266D01*
G02X190949Y551336I1940J1734D01*
G03X191549I300J264D01*
G02X195605Y548085I1950J-1723D01*
G03X195671Y547543I323J-236D01*
G02X195511Y543432I-1672J-1994D01*
G03X195444Y542841I232J-326D01*
G02X191549Y539390I-1945J-1728D01*
G03X190949I-300J-264D01*
G02X189580Y538577I-1949J1723D01*
G03X189380Y537911I89J-390D01*
G02X189222Y534163I-1881J-1798D01*
G03Y533563I264J-300D01*
G37*
G36*
G01X68913Y543973D02*
G02X65080Y545180I-2413J-973D01*
G01Y545588D01*
X65713Y546222D01*
X65706Y546314D01*
G02X70266Y546907I2294J185D01*
G03X70932Y546685I394J71D01*
G02X70992Y546739I1570J-1684D01*
G03X71014Y547019I-131J151D01*
G02X74505Y546577I1986J1681D01*
G01X74420Y546518D01*
Y546271D01*
X74451Y546222D01*
G02X70234Y544593I-1951J-1222D01*
G03X69568Y544815I-394J-71D01*
G02X69094Y544475I-1568J1685D01*
G03X68913Y543973I190J-352D01*
G37*
G36*
G01X750629Y1113044D02*
G02X746802Y1113523I-2130J-1494D01*
G03X746869Y1114056I-260J303D01*
G02X747597Y1117742I2130J1494D01*
G03X747731Y1118275I-215J337D01*
G02X752475Y1120350I2268J1275D01*
G03X753208Y1120283I381J123D01*
G02X753023Y1118250I2291J-1233D01*
G03X752290Y1118317I-381J-123D01*
G02X751401Y1117358I-2291J1233D01*
G03X751267Y1116825I215J-337D01*
G02X750696Y1113577I-2268J-1275D01*
G03X750629Y1113044I260J-303D01*
G37*
G36*
G01X868906Y1377860D02*
X868953Y1377889D01*
G02X868907Y1373458I1341J-2230D01*
G01X866576D01*
X866467Y1373497D01*
X866439Y1373499D01*
G02X864515Y1374811I157J2297D01*
G03X863813Y1374849I-361J-171D01*
G02X860428Y1377861I-1964J1201D01*
G01Y1381320D01*
G02Y1385680I1421J2180D01*
G01Y1434488D01*
X881828Y1455888D01*
Y1470212D01*
X870061Y1481980D01*
X797561D01*
X788080Y1491461D01*
Y1523461D01*
X784777Y1526763D01*
X784685Y1526756D01*
G02X786793Y1528864I-186J2294D01*
G01X786786Y1528772D01*
X790920Y1524637D01*
Y1492637D01*
X798737Y1484820D01*
X812223D01*
G03X812590Y1485380I0J400D01*
G02X816810I2110J920D01*
G03X817177Y1484820I367J-160D01*
G01X871237D01*
X884670Y1471388D01*
Y1454712D01*
X863270Y1433312D01*
Y1385680D01*
G02X863269Y1381320I-1421J-2180D01*
G01Y1377861D01*
G02X863930Y1377035I-1419J-1813D01*
G03X864632Y1376997I361J171D01*
G02X865094Y1377540I1963J-1202D01*
G03X865109Y1378132I-261J303D01*
G02X868358Y1378199I1591J1664D01*
G01X868302Y1378141D01*
Y1377860D01*
X868906D01*
G37*
G36*
G01X564542Y1488934D02*
G02X562456I-1043J-2384D01*
G03Y1489666I-161J366D01*
G02Y1494434I1043J2384D01*
G03Y1495166I-161J366D01*
G02X564542I1043J2384D01*
G03Y1494434I161J-366D01*
G02Y1489666I-1043J-2384D01*
G03Y1488934I161J-366D01*
G37*
G36*
G01X352068Y1582709D02*
G02X351080Y1584795I-2294J191D01*
G03X351706Y1585091I227J329D01*
G02X352694Y1583005I2294J-191D01*
G03X352068Y1582709I-227J-329D01*
G37*
G36*
G01X754634Y1764060D02*
G02X751271Y1768029I-1734J1940D01*
G03X751359Y1768555I-250J312D01*
G02X754997Y1772114I2199J1391D01*
G03X755525Y1772190I222J333D01*
G02X755657Y1772335I1989J-1678D01*
G03X755454Y1773006I-286J280D01*
G02X754265Y1773610I545J2544D01*
G03X753733I-266J-299D01*
G02X750370Y1777579I-1734J1940D01*
G03X750458Y1778105I-250J312D01*
G02X754096Y1781664I2199J1391D01*
G03X754624Y1781740I222J333D01*
G02X758027Y1777880I1993J-1673D01*
G03X757944Y1777278I216J-337D01*
G02X757860Y1773732I-1945J-1728D01*
G03X758063Y1773061I286J-280D01*
G02X758928Y1768330I-545J-2544D01*
G03X758845Y1767728I216J-337D01*
G02X755166Y1764060I-1946J-1728D01*
G03X754634I-266J-299D01*
G37*
G36*
G01X164743Y1792490D02*
G02X163649Y1790980I1157J-1990D01*
G03X163057Y1791410I-391J84D01*
G02X164151Y1792920I-1157J1990D01*
G03X164743Y1792490I391J-84D01*
G37*
G36*
G01X771383Y1929007D02*
G02Y1931093I-2384J1043D01*
G03X772115I366J161D01*
G02Y1929007I2384J-1043D01*
G03X771383I-366J-161D01*
G37*
G36*
G01X210497Y17348D02*
X187001D01*
X182798Y21552D01*
Y37348D01*
X109501D01*
X105798Y41052D01*
Y69048D01*
X109416Y72666D01*
G03X109133Y73348I-283J282D01*
G01X108001D01*
X105798Y75552D01*
Y114548D01*
X111001Y119752D01*
X179997D01*
X182200Y117548D01*
Y109331D01*
G03X182883Y109048I400J0D01*
G01X185387Y111552D01*
X193112D01*
G02X195886I1387J-2202D01*
G01X206862D01*
G02X208048Y111851I1136J-2002D01*
G01X208133Y111850D01*
X209535Y113252D01*
X214918D01*
G03X215201Y113934I0J400D01*
G01X214787Y114348D01*
X205886D01*
G02X203112I-1387J2202D01*
G01X197087D01*
X192837Y118598D01*
X189672D01*
X189645Y118590D01*
G02Y123010I-646J2210D01*
G01X189672Y123002D01*
X194661D01*
X198911Y118752D01*
X203112D01*
G02X205886I1387J-2202D01*
G01X216611D01*
X225700Y109662D01*
Y108823D01*
X225709Y108796D01*
G02X225801Y108151I-2210J-644D01*
G03X226201Y107752I400J1D01*
G01X235487D01*
X235866Y108131D01*
X235880Y108156D01*
G02X235960Y108291I2019J-1105D01*
G03X235792Y108598I-169J107D01*
G01X234422D01*
X234395Y108590D01*
G02Y113010I-646J2210D01*
G01X234422Y113002D01*
X239587D01*
X243300Y109288D01*
Y96437D01*
G02Y93663I-2201J-1387D01*
G01Y85738D01*
X232782Y75219D01*
X232768Y75194D01*
G02X232573Y74895I-2020J1104D01*
G03X232890Y74252I317J-243D01*
G01X235497D01*
X237200Y72548D01*
Y32552D01*
X234497Y29848D01*
X214501D01*
X213883Y30467D01*
G03X213200Y30184I-283J-283D01*
G01Y20052D01*
X210497Y17348D01*
G37*
G36*
G01X920497Y13848D02*
X900001D01*
X896797Y17052D01*
Y35184D01*
G03X896115Y35467I-400J0D01*
G01X895997Y35348D01*
X839001D01*
X834798Y39552D01*
Y76548D01*
X836550Y78300D01*
X833798Y81052D01*
Y126548D01*
X837501Y130252D01*
X892497D01*
X894700Y128048D01*
Y121331D01*
G03X895383Y121048I400J0D01*
G01X898087Y123752D01*
X903112D01*
G02X905886I1387J-2202D01*
G01X907587D01*
X908721Y124885D01*
X908732Y124947D01*
G02X911645Y126760I2268J-397D01*
G01X911672Y126752D01*
X912718D01*
G03X913001Y127434I0J400D01*
G01X910837Y129598D01*
X908172D01*
X908145Y129590D01*
G02Y134010I-646J2210D01*
G01X908172Y134002D01*
X912661D01*
X920117Y126545D01*
X920171Y126532D01*
G02X922067Y124636I-629J-2525D01*
G01X922080Y124582D01*
X924126Y122536D01*
G03X924792Y122705I283J283D01*
G02X926602Y124317I2207J-655D01*
G01X926664Y124328D01*
X930087Y127752D01*
X950497D01*
X962143Y116105D01*
X962197Y116092D01*
G02X964093Y114196I-629J-2525D01*
G01X964106Y114142D01*
X970900Y107348D01*
Y91338D01*
X965411Y85848D01*
X955749D01*
X955646Y85602D01*
X955700Y85548D01*
Y33552D01*
X951497Y29348D01*
X926501D01*
X924383Y31467D01*
G03X923700Y31184I-283J-283D01*
G01Y17052D01*
X920497Y13848D01*
G37*
G36*
G01X13069Y1142181D02*
G02X10699Y1143107I-3226J-4761D01*
G03X11057Y1143769I60J396D01*
G02X11957Y1147884I1943J1731D01*
G03Y1148616I-161J366D01*
G02X11344Y1153007I1043J2384D01*
G03X11089Y1153716I-254J309D01*
G01X9391D01*
G03X9072Y1153074I0J-400D01*
G02X7800Y1149024I-2072J-1574D01*
G03X7733Y1148291I123J-381D01*
G02X5700Y1148476I-1233J-2291D01*
G03X5767Y1149209I-123J381D01*
G02X4928Y1153074I1233J2291D01*
G03X4609Y1153716I-319J242D01*
G01X4258D01*
Y1158918D01*
X20862D01*
Y1158518D01*
X21144D01*
X21171Y1158527D01*
G02Y1154107I646J-2210D01*
G01X21144Y1154116D01*
X20862D01*
Y1153716D01*
X14911D01*
G03X14656Y1153007I-1J-400D01*
G02X15139Y1152482I-1655J-2008D01*
G03X15738Y1152415I329J228D01*
G02X19134Y1148475I1762J-1915D01*
G03X19200Y1147809I251J-311D01*
G02X15833Y1144060I-1200J-2309D01*
G03X15167I-333J-222D01*
G02X13255Y1142910I-2168J1440D01*
G03X13069Y1142181I39J-398D01*
G37*
G36*
G01X47000Y1734788D02*
X43600D01*
G02Y1739412I0J2312D01*
G01X47000D01*
G02X49312Y1737110I0J-2312D01*
G01Y1737012D01*
X49305Y1736924D01*
G02X47000Y1734788I-2305J176D01*
G37*
G36*
G01X48188Y1728487D02*
Y1724735D01*
X48182Y1724647D01*
G02X43566Y1724823I-2305J176D01*
G01Y1728478D01*
G02X48188Y1728487I2311J-1D01*
G37*
G36*
G01X96200Y1668162D02*
Y1667830D01*
X96580Y1667450D01*
G02X93480Y1664312I-1081J-2032D01*
G01X93466Y1664337D01*
X91798Y1666006D01*
Y1668163D01*
G02X96229Y1668209I2201J1387D01*
G01X96200Y1668162D01*
G37*
G36*
G01X66913Y486302D02*
X66911Y486244D01*
X66910Y486243D01*
G02X62290Y486368I-2310J57D01*
G01X62390Y489768D01*
G02X67012Y489710I2311J-68D01*
G01Y489666D01*
X66912Y486302D01*
X66913D01*
G37*
G36*
G01X92585Y483986D02*
G03X92719Y484652I-140J375D01*
G02X95945Y488713I1780J1898D01*
G03X96544Y488913I222J333D01*
G02X97553Y485887I2455J-863D01*
G03X96954Y485687I-222J-333D01*
G02X95413Y484114I-2455J863D01*
G03X95279Y483448I140J-375D01*
G02X95319Y483409I-1796J-1882D01*
G03X95879I280J286D01*
G02X99422Y479600I1820J-1859D01*
G03Y479000I264J-300D01*
G02X95879Y475191I-1723J-1950D01*
G03X95319I-280J-286D01*
G02X91776Y479000I-1820J1859D01*
G03Y479600I-264J300D01*
G02X92585Y483986I1723J1950D01*
G37*
G36*
G01X66708Y474442D02*
X66715Y470960D01*
X66708Y470870D01*
G02X62092Y471042I-2305J177D01*
G01X62086Y474442D01*
G02X66701Y474631I2311J4D01*
G01X66708Y474539D01*
Y474442D01*
G37*
G36*
G01X177874Y440452D02*
G03X177920Y440985I-273J292D01*
G02X178276Y444500I2079J1565D01*
G03Y445100I-264J300D01*
G02X181733Y448990I1723J1950D01*
G03X182265I266J299D01*
G02X185722Y445100I1734J-1940D01*
G03Y444500I264J-300D01*
G02X185939Y440816I-1723J-1950D01*
G03Y440284I299J-266D01*
G02X182114Y436757I-1940J-1734D01*
G03X181534I-290J-276D01*
G02X177874Y440452I-1885J1793D01*
G37*
G54D29*
X895669Y1975079D03*
Y1801851D03*
Y1569567D03*
Y1396339D03*
Y1164055D03*
Y990827D03*
Y758543D03*
Y585315D03*
Y353031D03*
Y179803D03*
X167323Y1975079D03*
Y1801851D03*
Y1569567D03*
Y758543D03*
Y585315D03*
Y353031D03*
Y179803D03*
X68898Y17047D03*
G54D34*
X88000Y36400D03*
X129400Y426900D03*
X145649Y509550D03*
X180000Y1619600D03*
X307999Y78550D03*
X305998Y352114D03*
X334999Y1797050D03*
X326301Y1766030D03*
X563499Y1503550D03*
X544300Y1784638D03*
X633837Y1807384D03*
X748000Y357500D03*
X751499Y679148D03*
X750000Y755500D03*
X747000Y1159000D03*
X757500Y1522500D03*
X717000Y1812384D03*
X750000Y1965500D03*
X767159Y1792364D03*
X767999Y1923050D03*
X773999Y1923550D03*
X903999Y574378D03*
X873499Y1356050D03*
X904814Y1789113D03*
X950100Y1626100D03*
X21500Y1122500D03*
X135999Y472550D03*
X135140Y478930D03*
X149700Y471600D03*
X154100Y476500D03*
X164600Y476700D03*
X171300D03*
X154099Y529236D03*
G54D35*
X65999Y216050D03*
X95350Y204550D03*
X89800Y208550D03*
X97499Y90050D03*
X173500Y166315D03*
X165500Y416500D03*
X135499Y517550D03*
X137899Y545451D03*
X156500Y554000D03*
X107000Y604800D03*
X105100Y600000D03*
X171999Y1662250D03*
X174250Y1694500D03*
X152633Y1677967D03*
X177900Y1690400D03*
X247800Y269700D03*
X225298Y281114D03*
X250300Y275100D03*
X250400Y283100D03*
X239600Y278600D03*
X199900Y554050D03*
X220000Y516400D03*
X183499Y556100D03*
X246800Y677100D03*
X249700Y682500D03*
X249800Y689900D03*
X238500Y680800D03*
X226800Y1093400D03*
X233500Y1066100D03*
X221800Y1069300D03*
X247500Y1085500D03*
X251500Y1136700D03*
X182500Y1275500D03*
X199149Y1362900D03*
X241000Y1469600D03*
X224750Y1483950D03*
X195000Y1645500D03*
X181100Y1682700D03*
X257499Y1911050D03*
X249600Y1896800D03*
X323400Y105200D03*
X282800Y87500D03*
X297499Y97550D03*
X293999Y293550D03*
X344520Y406329D03*
X329499Y801550D03*
X330540Y795509D03*
X320499Y798050D03*
X340699Y1046086D03*
X282500Y1135000D03*
X269500Y1135500D03*
X326500Y1550200D03*
X295000Y1513000D03*
X333000Y1578000D03*
X330300Y1561200D03*
X330500Y1966500D03*
X310499Y1957050D03*
X358999Y61550D03*
X400499Y406329D03*
X371999Y549300D03*
X394649Y630600D03*
X350499Y597300D03*
X375999Y698550D03*
X350499Y715050D03*
X371500Y880600D03*
X364499Y1099050D03*
X372999Y1123550D03*
X345499Y1096550D03*
X370149Y1320050D03*
X345424Y1310050D03*
X347324Y1524000D03*
X366149Y1554050D03*
X402499Y1476850D03*
X354500Y1559500D03*
X400999Y1575550D03*
X377900Y1703800D03*
X757499Y1079550D03*
X757999Y1484050D03*
X750000Y1560500D03*
X733149Y1798634D03*
X732549Y1806634D03*
X733049Y1814134D03*
X707600Y1815600D03*
X758499Y1893550D03*
X837999Y219550D03*
X827500Y274500D03*
X809940Y264940D03*
X780499Y330050D03*
X829800Y666650D03*
X781999Y725550D03*
X808660Y667540D03*
X825700Y1083100D03*
X807000Y1072900D03*
X827700Y1487600D03*
X809960Y1478040D03*
X828500Y1877800D03*
X822700Y1871100D03*
X800431Y1941193D03*
X802499Y1951550D03*
X916499Y172550D03*
X854400Y264600D03*
X902999Y556050D03*
X879750Y570550D03*
X879950Y565050D03*
X852696Y671197D03*
X900499Y962100D03*
X879708Y971892D03*
X900999Y979050D03*
X883083Y979183D03*
X852333Y1077716D03*
X854327Y1477550D03*
X42199Y1601050D03*
X24244Y1681868D03*
X98599Y1491350D03*
X163449Y521650D03*
G54D32*
X78150Y28858D03*
Y178464D03*
X158071Y191614D03*
Y341220D03*
Y597126D03*
Y1557756D03*
Y1813662D03*
Y1963268D03*
X886417Y191614D03*
Y341220D03*
Y597126D03*
Y746732D03*
Y1002638D03*
Y1152244D03*
Y1408150D03*
Y1557756D03*
Y1813662D03*
Y1963268D03*
X78150Y1650906D03*
G54D30*
X9843Y153168D03*
Y265767D03*
Y353144D03*
Y1859468D03*
Y1746869D03*
G54D33*
X1019291Y1416024D03*
G54D31*
X21499Y17050D03*
X1010999Y18550D03*
X1008999Y1968550D03*
G54D36*
X29532Y309561D03*
X271657Y267711D03*
Y673223D03*
Y1078734D03*
Y1484246D03*
X994098Y149601D03*
Y673223D03*
X994099Y1068892D03*
X994093Y1889751D03*
%LPD*%
G75*
G36*
G01X201999Y72550D02*
X202999Y71550D01*
Y58550D01*
X182999Y38550D01*
X109999D01*
X106999Y41550D01*
Y68550D01*
X110999Y72550D01*
X201999D01*
G37*
G36*
G01X172798Y77612D02*
X175975Y74434D01*
G02X175692Y73752I-283J-282D01*
G01X169865D01*
G02X169582Y74434I0J400D01*
G01X171700Y76552D01*
Y86291D01*
G02X172383Y86574I400J0D01*
G01X173466Y85491D01*
X173480Y85466D01*
G03X176265Y84401I2019J1106D01*
G02X176798Y84024I133J-377D01*
G01Y81362D01*
G02X176191Y81020I-400J0D01*
G03X172789Y78404I-1192J-1970D01*
G01X172798Y78377D01*
Y77612D01*
G37*
G36*
G01X108499Y74550D02*
X106999Y76050D01*
Y114050D01*
X111499Y118550D01*
X179499D01*
X180999Y117050D01*
Y109050D01*
X170499Y98550D01*
Y77050D01*
X167999Y74550D01*
X108499D01*
G37*
G36*
G01X187499Y18550D02*
X183999Y22050D01*
Y37050D01*
X195499Y48550D01*
X208999D01*
X211999Y45550D01*
Y20550D01*
X209999Y18550D01*
X187499D01*
G37*
G36*
G01X212615Y46633D02*
X209497Y49752D01*
X196865D01*
G02X196582Y50434I0J400D01*
G01X204200Y58052D01*
Y72048D01*
X202497Y73752D01*
X182306D01*
G02X182023Y74434I0J400D01*
G01X188730Y81141D01*
Y96848D01*
X194112D01*
G03X196886I1387J2202D01*
G01X208811D01*
X214580Y102618D01*
G03X215447Y103424I-1081J2032D01*
G02X216068Y103493I338J-214D01*
G01X223298Y96264D01*
Y74252D01*
X220001D01*
X217798Y72048D01*
Y56048D01*
X213298Y51548D01*
Y46916D01*
G02X212615Y46633I-400J0D01*
G37*
G36*
G01X233999Y31050D02*
X214999D01*
X214499Y31550D01*
Y51050D01*
X218999Y55550D01*
Y71550D01*
X220499Y73050D01*
X234999D01*
X235999Y72050D01*
Y33050D01*
X233999Y31050D01*
G37*
G36*
G01X177819Y97756D02*
X187211Y107148D01*
X193112D01*
G03X195886I1387J2202D01*
G01X203077D01*
G02X203436Y106571I1J-400D01*
G03X206145Y103340I2063J-1021D01*
G01X206172Y103348D01*
X208118D01*
G02X208401Y102666I0J-400D01*
G01X206987Y101252D01*
X196886D01*
G03X194112I-1387J-2202D01*
G01X187672D01*
X187645Y101260D01*
G03X184980Y100156I-646J-2210D01*
G01X184966Y100131D01*
X184326Y99491D01*
Y82965D01*
X181883Y80522D01*
G02X181200Y80805I-283J283D01*
G01Y87163D01*
G03Y89937I-2201J1387D01*
G01Y94784D01*
X178911Y97074D01*
X178102D01*
G02X177819Y97756I0J400D01*
G37*
G36*
G01X343499Y98550D02*
X270499Y171550D01*
X221499D01*
X220999Y172050D01*
Y204999D01*
X222000Y206000D01*
X262181D01*
X262200Y205996D01*
G03X263198I499J2554D01*
G01X263217Y206000D01*
X286500D01*
X319310Y173190D01*
X319325Y173144D01*
G03X320993Y171476I2474J806D01*
G01X321039Y171461D01*
X374500Y118000D01*
Y100500D01*
X372550Y98550D01*
X343499D01*
G37*
G36*
G01X289499Y28101D02*
Y35050D01*
X303499Y49050D01*
X310999D01*
X311999Y48050D01*
Y33050D01*
X305349Y26400D01*
X291200D01*
X289499Y28101D01*
G37*
G36*
G01X836999Y77050D02*
X886499D01*
X895499Y86050D01*
X919499D01*
X920499Y85050D01*
Y61550D01*
X895499Y36550D01*
X839499D01*
X835999Y40050D01*
Y76050D01*
X836999Y77050D01*
G37*
G36*
G01X882999Y79550D02*
X836999D01*
X834999Y81550D01*
Y126050D01*
X837999Y129050D01*
X891999D01*
X893499Y127550D01*
Y90050D01*
X882999Y79550D01*
G37*
G36*
G01X900499Y15050D02*
X897999Y17550D01*
Y37050D01*
X910999Y50050D01*
X920999D01*
X922499Y48550D01*
Y17550D01*
X919999Y15050D01*
X900499D01*
G37*
G36*
G01X923115Y49633D02*
X921497Y51252D01*
X912865D01*
G02X912582Y51934I0J400D01*
G01X921700Y61052D01*
Y85548D01*
X919997Y87252D01*
X895001D01*
X886001Y78251D01*
X884365D01*
G02X884082Y78934I0J400D01*
G01X894700Y89552D01*
Y89752D01*
G02X895042Y89894I200J1D01*
G01X895522Y89413D01*
X895536Y89388D01*
G03X899759Y89829I2019J1106D01*
G02X900343Y90059I383J-116D01*
G03X903518Y90944I1156J1991D01*
G01X903532Y90969D01*
X903800Y91238D01*
Y92002D01*
X903801Y92004D01*
G03Y92096I-2302J46D01*
G01X903800Y92098D01*
Y101362D01*
X901461Y103701D01*
X901495Y103815D01*
G03X901200Y105937I-2496J735D01*
G01Y107769D01*
G02X901883Y108052I400J0D01*
G01X905087Y104848D01*
X917112D01*
G03X919886I1387J2202D01*
G01X929411D01*
X936700Y112138D01*
Y113238D01*
G02X937307Y113580I400J0D01*
G03X940463Y114348I1192J1970D01*
G01X944112D01*
G03X946886I1387J2202D01*
G01X952587D01*
X963298Y103638D01*
Y95552D01*
X962172D01*
X962145Y95560D01*
G03Y91140I-646J-2210D01*
G01X962172Y91148D01*
X963518D01*
G02X963801Y90466I0J-400D01*
G01X963587Y90252D01*
X948087D01*
X945087Y87252D01*
X936001D01*
X930798Y82048D01*
Y73048D01*
X923798Y66048D01*
Y49916D01*
G02X923115Y49633I-400J0D01*
G37*
G36*
G01X898636Y92526D02*
X898000Y93162D01*
Y99969D01*
G02X898683Y100252I400J0D01*
G01X899398Y99538D01*
Y92990D01*
G03X899295Y92715I2100J-943D01*
G02X898711Y92485I-383J116D01*
G03X898636Y92526I-1141J-1999D01*
G37*
G36*
G01X911999Y121937D02*
X921087Y112848D01*
X926326D01*
X926353Y112840D01*
G03X928893Y113742I645J2210D01*
G02X929485Y113816I329J-228D01*
G03X930695Y113268I1514J1734D01*
G02X930925Y112589I-53J-396D01*
G01X927587Y109252D01*
X919886D01*
G03X917112I-1387J-2202D01*
G01X906911D01*
X904531Y111631D01*
G03X900889Y112195I-2032J-1081D01*
G02X900609I-140J143D01*
G03X898489Y112795I-1610J-1645D01*
G02X898000Y113185I-89J390D01*
G01Y117438D01*
X899911Y119348D01*
X903112D01*
G03X905886I1387J2202D01*
G01X909411D01*
X911999Y121937D01*
G37*
G36*
G01X935039Y84590D02*
X936499Y86050D01*
X953499D01*
X954499Y85050D01*
Y34050D01*
X950999Y30550D01*
X926999D01*
X924999Y32550D01*
Y65550D01*
X931999Y72550D01*
Y81550D01*
X933952Y83503D01*
X933981Y83518D01*
G03X935024Y84561I-1020J2063D01*
G01X935039Y84590D01*
G37*
G36*
G01X948673Y123348D02*
X952587Y119434D01*
G02X952304Y118752I-283J-282D01*
G01X946886D01*
G03X944112I-1387J-2202D01*
G01X940200D01*
Y121377D01*
X940209Y121404D01*
G03X940170Y122816I-2210J646D01*
G02X940547Y123348I377J132D01*
G01X948673D01*
G37*
G54D10*
X-30766Y56622D03*
X-33866Y1947322D03*
X21499Y17050D03*
X1010999Y18550D03*
X1008999Y1968550D03*
X1073334Y50022D03*
G54D11*
X-39052Y28742D03*
X9843Y153168D03*
Y265767D03*
X-43327Y310478D03*
X9843Y353144D03*
Y717711D03*
Y762617D03*
Y875216D03*
X-39686Y917251D03*
X9843Y1137420D03*
X-38801Y1082342D03*
X9843Y1250019D03*
X-44886Y1294251D03*
X9843Y1337396D03*
Y1701963D03*
Y1746869D03*
Y1859468D03*
X-43103Y1928864D03*
X78150Y28858D03*
Y178464D03*
Y434370D03*
Y583976D03*
Y839882D03*
Y989488D03*
Y1245394D03*
Y1395000D03*
Y1650906D03*
Y1800512D03*
X158071Y191614D03*
Y341220D03*
Y597126D03*
Y746732D03*
Y1002638D03*
Y1152244D03*
Y1408150D03*
Y1557756D03*
Y1813662D03*
Y1963268D03*
X886417Y191614D03*
Y341220D03*
Y597126D03*
Y746732D03*
Y1002638D03*
Y1152244D03*
Y1408150D03*
Y1557756D03*
Y1813662D03*
Y1963268D03*
X1071932Y32074D03*
X1074813Y1348051D03*
X1019291Y1416024D03*
Y1694212D03*
X1076613Y1740651D03*
X1074813Y1957551D03*
G54D20*
X1005807Y1636102D03*
Y1631102D03*
Y1626102D03*
Y1621102D03*
Y1676102D03*
Y1671102D03*
Y1666102D03*
Y1661102D03*
Y1656102D03*
Y1651102D03*
Y1646102D03*
Y1641102D03*
G54D21*
G01X-71137Y-139897D02*
Y-219897D01*
G01D02*
X1129963D01*
G01X-75137Y-123897D02*
G02I-12000J0D01*
G01X-80287D02*
G02I-6850J0D01*
G01X-87137Y-139897D02*
Y-107897D01*
G01X-71137Y-123897D02*
X-103137D01*
G01X-71137Y-139897D02*
X1129963D01*
G01X-71137Y-175397D02*
X1129963D01*
G01X24000Y116500D02*
Y169000D01*
X20935Y172065D01*
X11060D01*
G01X23499Y381831D02*
X21472Y383858D01*
X11075D01*
X11069Y383852D01*
G01X23399Y389679D02*
X21515Y387795D01*
X11075D01*
X11069Y387789D01*
G01X23399Y373931D02*
X21515Y372047D01*
X11075D01*
X11069Y372041D01*
G01X23600Y405700D02*
X21443Y403543D01*
X11075D01*
X11069Y403537D01*
G01X23499Y397579D02*
X21472Y399606D01*
X11075D01*
X11069Y399600D01*
G01X23499Y436951D02*
X21472Y438978D01*
X11075D01*
X11069Y438972D01*
G01X23399Y429051D02*
X21515Y427167D01*
X11075D01*
X11069Y427161D01*
G01X23399Y460547D02*
X21515Y458663D01*
X11075D01*
X11069Y458657D01*
G01X23499Y452699D02*
X21472Y454726D01*
X11075D01*
X11069Y454720D01*
G01X23399Y444799D02*
X21515Y442915D01*
X11075D01*
X11069Y442909D01*
G01X23399Y476295D02*
X21515Y474411D01*
X11075D01*
X11069Y474405D01*
G01X23499Y468447D02*
X21472Y470474D01*
X11075D01*
X11069Y470468D01*
G01X23499Y484195D02*
X21472Y486222D01*
X11075D01*
X11069Y486216D01*
G01X23399Y507791D02*
X21515Y505907D01*
X11075D01*
X11069Y505901D01*
G01X23499Y499943D02*
X21472Y501970D01*
X11075D01*
X11069Y501964D01*
G01X23399Y492043D02*
X21515Y490159D01*
X11075D01*
X11069Y490153D01*
G01X23499Y531439D02*
X21472Y533466D01*
X11075D01*
X11069Y533460D01*
G01X23399Y523539D02*
X21515Y521655D01*
X11075D01*
X11069Y521649D01*
G01X23499Y515691D02*
X21472Y517718D01*
X11075D01*
X11069Y517712D01*
G01X22699Y577950D02*
X21522Y576773D01*
X11075D01*
X11069Y576767D01*
G01X22978Y588571D02*
X22965Y588584D01*
X11075D01*
X11069Y588578D01*
G01X23999Y609250D02*
X23018Y608269D01*
X11075D01*
X11069Y608263D01*
G01X23499Y633801D02*
X21472Y635828D01*
X11075D01*
X11069Y635822D01*
G01X23799Y625950D02*
X21866Y624017D01*
X11075D01*
X11069Y624011D01*
G01X23499Y618053D02*
X21472Y620080D01*
X11075D01*
X11069Y620074D01*
G01X23399Y641649D02*
X21515Y639765D01*
X11075D01*
X11069Y639759D01*
G01X23725Y657471D02*
X21767Y655513D01*
X11075D01*
X11069Y655507D01*
G01X23499Y649549D02*
X21373Y651675D01*
X21274Y651576D01*
X11075D01*
X11069Y651570D01*
G01X23499Y681045D02*
X21472Y683072D01*
X11075D01*
X11069Y683066D01*
G01X23699Y673150D02*
X21810Y671261D01*
X11075D01*
X11069Y671255D01*
G01X23499Y665297D02*
X21472Y667324D01*
X11075D01*
X11069Y667318D01*
G01X14900Y1086100D02*
X8900D01*
X8750Y1086250D01*
G01X11060Y1156317D02*
X21817D01*
G01X23499Y1382601D02*
X22242Y1383858D01*
X11075D01*
X11069Y1383852D01*
G01X23700Y1354600D02*
X22001Y1356299D01*
X11075D01*
X11069Y1356293D01*
G01X22999Y1366050D02*
X20939Y1368110D01*
X11075D01*
X11069Y1368104D01*
G01X22851Y1374169D02*
X20729Y1372047D01*
X11075D01*
X11069Y1372041D01*
G01X24499Y1389663D02*
X22631Y1387795D01*
X11075D01*
X11069Y1387789D01*
G01X23999Y1413550D02*
X21868Y1411419D01*
X11075D01*
X11069Y1411413D01*
G01X23499Y1421550D02*
X21819Y1423230D01*
X11075D01*
X11069Y1423224D01*
G01X23999Y1429050D02*
X22116Y1427167D01*
X11075D01*
X11069Y1427161D01*
G01X22999Y1437050D02*
X20972Y1439077D01*
X20873Y1438978D01*
X11075D01*
X11069Y1438972D01*
G01X23499Y1445050D02*
Y1444650D01*
X21764Y1442915D01*
X11075D01*
X11069Y1442909D01*
G01X22999Y1453050D02*
X21224Y1454825D01*
X21125Y1454726D01*
X11075D01*
X11069Y1454720D01*
G01X23499Y1460550D02*
X21612Y1458663D01*
X11075D01*
X11069Y1458657D01*
G01X23028Y1468579D02*
X21034Y1470573D01*
X20935Y1470474D01*
X11075D01*
X11069Y1470468D01*
G01X23599Y1476350D02*
X21660Y1474411D01*
X11075D01*
X11069Y1474405D01*
G01X23277Y1484050D02*
X21105Y1486222D01*
X11075D01*
X11069Y1486216D01*
G01X24499Y1492050D02*
X22608Y1490159D01*
X11075D01*
X11069Y1490153D01*
G01X23799Y1508050D02*
Y1507450D01*
X22256Y1505907D01*
X11075D01*
X11069Y1505901D01*
G01X22999Y1515550D02*
X20831Y1517718D01*
X11075D01*
X11069Y1517712D01*
G01X22999Y1500050D02*
X21079Y1501970D01*
X11075D01*
X11069Y1501964D01*
G01X24323Y1559950D02*
X23248Y1561025D01*
X11075D01*
X11069Y1561019D01*
G01X23608Y1572653D02*
X23425Y1572836D01*
X11075D01*
X11069Y1572830D01*
G01X23499Y1602050D02*
X21217Y1604332D01*
X11075D01*
X11069Y1604326D01*
G01X23499Y1610050D02*
X21718Y1608269D01*
X11075D01*
X11069Y1608263D01*
G01X22699Y1594224D02*
X20996Y1592521D01*
X11075D01*
X11069Y1592515D01*
G01X23499Y1618050D02*
X21469Y1620080D01*
X11075D01*
X11069Y1620074D01*
G01X23499Y1634050D02*
X21721Y1635828D01*
X11075D01*
X11069Y1635822D01*
G01X22999Y1626050D02*
X20966Y1624017D01*
X11075D01*
X11069Y1624011D01*
G01X23415Y1641634D02*
X21546Y1639765D01*
X11075D01*
X11069Y1639759D01*
G01X23999Y1649550D02*
X21973Y1651576D01*
X11075D01*
X11069Y1651570D01*
G01X23499Y1657050D02*
X21962Y1655513D01*
X11075D01*
X11069Y1655507D01*
G01X22999Y1665550D02*
X21225Y1667324D01*
X11075D01*
X11069Y1667318D01*
G01X8499Y1937550D02*
Y1944024D01*
X8503Y1944028D01*
Y1956700D01*
G01X31799Y1979050D02*
X25947D01*
X8503Y1961606D01*
Y1956700D01*
G01X5303Y1947050D02*
X5000Y1946747D01*
Y1935900D01*
X12119Y1928781D01*
X17455D01*
G01X11703Y1951946D02*
Y1942702D01*
X11699Y1942698D01*
Y1934824D01*
X13674Y1932849D01*
X23999D01*
G01X15750Y102250D02*
X24000Y110500D01*
Y116500D01*
G01X93299Y862050D02*
X96000Y864751D01*
Y866000D01*
G01X93900Y882400D02*
X93750Y882550D01*
X88999D01*
G01X93808Y852063D02*
X93795Y852050D01*
X92450D01*
X90000Y854500D01*
G01X93499Y892050D02*
X89499D01*
G01X24000Y853500D02*
X24500D01*
X43600Y872600D01*
Y883700D01*
G01D02*
Y886500D01*
X33600Y896500D01*
X29000D01*
G01X67000Y1011500D02*
X67211D01*
X78099Y1000612D01*
Y999373D01*
X96972Y980500D01*
X104600D01*
G01X88000Y1008500D02*
X91100D01*
X99200Y1000400D01*
Y994200D01*
G01X75500Y1012261D02*
X93939D01*
X103900Y1002300D01*
Y999400D01*
G01X95499Y1665418D02*
X93999Y1666918D01*
Y1669550D01*
G01Y1703050D02*
X89999D01*
G01X89200Y1832000D02*
Y1828700D01*
X90000Y1827900D01*
G01X40500Y1863000D02*
X41500D01*
X45900Y1862900D01*
G01X15099Y1944050D02*
Y1953250D01*
X13799Y1954550D01*
Y1962376D01*
X19172Y1967749D01*
X37499D01*
G01X47598Y1961550D02*
X41399Y1967749D01*
X37499D01*
G01X43462Y1961160D02*
X40073Y1964549D01*
X32999D01*
G01D02*
X20498D01*
X17499Y1961550D01*
Y1961050D01*
G01D02*
X16999Y1960550D01*
Y1958050D01*
X18299Y1956750D01*
Y1939350D01*
X14999Y1936050D01*
G01X32999Y1960555D02*
Y1956855D01*
G01X23030Y1922038D02*
Y1923206D01*
X17455Y1928781D01*
G01X42499Y1902550D02*
Y1923550D01*
X35521Y1930528D01*
G01X25499Y1956050D02*
Y1940550D01*
X35521Y1930528D01*
G01X48499Y1897050D02*
X43472D01*
X38999Y1901523D01*
Y1921050D01*
X27200Y1932849D01*
X23999D01*
G01X57999Y1891050D02*
X47999D01*
G01X26765Y1921945D02*
X29591D01*
X34970Y1916566D01*
Y1901026D01*
X44946Y1891050D01*
X47999D01*
G01X186999Y99050D02*
X186528Y98579D01*
Y82053D01*
X180325Y75850D01*
X177673D01*
X174999Y78524D01*
Y79050D01*
G01X175499Y86572D02*
X173199Y88872D01*
Y96199D01*
X174999Y97999D01*
Y98050D01*
X186299Y109350D01*
X194499D01*
G01X176399Y94872D02*
X177999D01*
X178999Y93872D01*
Y88550D01*
G01X154200Y168500D02*
X156817Y165883D01*
G01X149400Y166400D02*
Y162500D01*
G01X136349Y509050D02*
X132349D01*
G01X153499Y502550D02*
X157499D01*
G01X138416Y553500D02*
X138116Y553800D01*
X134700D01*
G01X157000Y573851D02*
X156700Y574000D01*
X153000D01*
G01X141300Y565900D02*
Y566200D01*
X137100Y570400D01*
Y570500D01*
G01X160824Y577000D02*
X160900Y576700D01*
Y573000D01*
G01X99200Y994200D02*
Y989364D01*
X103200Y985364D01*
G01X103900Y999400D02*
Y993300D01*
X104700Y992500D01*
Y989900D01*
G01X101541Y1262607D02*
X102556D01*
X104999Y1265050D01*
G01X116999Y1288050D02*
X116499D01*
X113999Y1285550D01*
G01X101399Y1292550D02*
X105499D01*
G01X140000Y1332600D02*
X139400Y1332900D01*
X136783Y1335517D01*
G01X147400Y1321600D02*
X145500Y1323500D01*
X143500D01*
G01X118499Y1694050D02*
Y1697750D01*
G01X213499Y104650D02*
X207899Y99050D01*
X195499D01*
G01D02*
X186999D01*
G01X188999Y120800D02*
X193749D01*
X197999Y116550D01*
X204499D01*
G01X223499Y108150D02*
Y108750D01*
X215699Y116550D01*
X204499D01*
G01X225499Y68550D02*
Y97176D01*
X214825Y107850D01*
X211773D01*
X209473Y105550D01*
X205499D01*
G01X230749Y76300D02*
X241099Y86650D01*
Y95050D01*
G01X233749Y110800D02*
X238675D01*
X241099Y108376D01*
Y95050D01*
G01X237899Y107050D02*
X236399Y105550D01*
X221651D01*
X216151Y111050D01*
X210447D01*
X208947Y109550D01*
X207999D01*
G01D02*
X207799Y109350D01*
X194499D01*
G01X178999Y79050D02*
Y88550D01*
G01X229800Y1073600D02*
Y1077300D01*
G01X242000Y1066000D02*
Y1069700D01*
G01X181000Y1365500D02*
Y1361000D01*
G01X180500Y1369900D02*
X180400Y1370000D01*
Y1374000D01*
G01X229800Y1872000D02*
Y1875700D01*
G01X218100Y1886400D02*
Y1882700D01*
G01X213138Y1952703D02*
X215485Y1955050D01*
X215999D01*
G01X249499Y1928050D02*
Y1924350D01*
G01X231999Y1914050D02*
Y1918050D01*
G01X210999Y1942050D02*
Y1945750D01*
G01X214999Y1909550D02*
Y1914050D01*
G01X342463Y-139897D02*
Y-219897D01*
G01X343499Y31650D02*
X343630Y31519D01*
X347328D01*
G01X354999Y72050D02*
X348499D01*
X335574Y84975D01*
X311074D01*
X308999Y87050D01*
G01X289999Y72550D02*
X285999D01*
G01X308499D02*
X312499D01*
G01X315800Y100500D02*
Y104200D01*
G01X324800Y89400D02*
Y93100D01*
G01X264499Y1964050D02*
Y1968050D01*
G01X479963Y-139897D02*
Y-219897D01*
G01X594963Y-139897D02*
Y-219897D01*
G01X751539Y313984D02*
Y301010D01*
X773049Y279500D01*
X822100D01*
G01X762463Y-139897D02*
Y-219897D01*
G01X822100Y279500D02*
X841075D01*
X842499Y280924D01*
G01X822100Y261700D02*
X822200Y261600D01*
Y258000D01*
G01X816700Y274300D02*
X816500Y274100D01*
Y270600D01*
G01X820600Y664300D02*
X820900Y664600D01*
Y668000D01*
G01X813200Y675900D02*
X812800Y676200D01*
Y679900D01*
G01X799385Y757436D02*
Y761436D01*
G01X825800Y1072300D02*
X825500Y1072600D01*
Y1076300D01*
G01X815400Y1082500D02*
Y1078800D01*
G01X806899Y1151850D02*
X803199D01*
G01X804899Y1553250D02*
Y1556950D01*
G01X802099Y1961950D02*
X801914D01*
X799297Y1959333D01*
G01X834799Y1946950D02*
X835114Y1947265D01*
Y1951150D01*
G01X907499Y131800D02*
X911749D01*
X919542Y124007D01*
G01X930999Y115550D02*
X927999Y118550D01*
X924999D01*
X919542Y124007D01*
G01X934499Y118750D02*
Y113050D01*
X928499Y107050D01*
X918499D01*
G01X902499Y110550D02*
X905999Y107050D01*
X918499D01*
G01X898999Y110550D02*
Y104550D01*
G01X901499Y92050D02*
X901599Y92150D01*
Y100450D01*
X898999Y103050D01*
Y104550D01*
G01X926999Y115050D02*
X921999D01*
X912499Y124550D01*
X910999D01*
G01D02*
Y124050D01*
X908499Y121550D01*
X904499D01*
G01X897555Y90494D02*
X895799Y92250D01*
Y118350D01*
X898999Y121550D01*
X904499D01*
G01X868799Y294750D02*
X872873D01*
X872999Y294624D01*
G01X865499Y288050D02*
X869325D01*
X869399Y288124D01*
G01X867899Y321550D02*
X864225D01*
X864199Y321524D01*
G01X868299Y336150D02*
X872525D01*
X872599Y336224D01*
G01X870499Y724550D02*
X866499D01*
G01X864499Y1128750D02*
X868750D01*
G01X866596Y1375796D02*
X866968Y1375659D01*
X870294D01*
G01X867523Y1542821D02*
X867180Y1542478D01*
X863838D01*
G01X867199Y1535150D02*
X865061Y1532096D01*
X864799Y1532050D01*
G01X863699Y1501250D02*
X866416Y1498533D01*
X866516D01*
G01X886439Y1717600D02*
Y1720939D01*
X886500Y1721000D01*
Y1721294D01*
X886506Y1721300D01*
G01X862800Y1712700D02*
X860286Y1715214D01*
X860085D01*
G01X889800Y1711500D02*
X892517Y1714217D01*
G01X873300Y1740100D02*
Y1740300D01*
X870783Y1742817D01*
G01X864414Y1944050D02*
Y1940050D01*
G01X863699Y1902750D02*
Y1906450D01*
G01X857099Y1917650D02*
X857500Y1917500D01*
X861000D01*
G01X932463Y-139897D02*
Y-219897D01*
G01X945499Y116550D02*
X939499D01*
X938499Y115550D01*
G01D02*
Y116550D01*
X937999Y117050D01*
Y122050D01*
G01X962750Y93350D02*
X964299D01*
X965499Y94550D01*
Y104550D01*
X953499Y116550D01*
X945499D01*
G01X962750Y93350D02*
X961499D01*
G01X943499Y82550D02*
X948999Y88050D01*
X964499D01*
X968699Y92250D01*
Y106436D01*
X961568Y113567D01*
G01X926999Y122050D02*
X927499D01*
X930999Y125550D01*
X949585D01*
X961568Y113567D01*
G01X1004307Y1621102D02*
X984300D01*
X981200Y1618002D01*
G01X1004307Y1656102D02*
X990998D01*
X988800Y1658300D01*
G01X1004307Y1666102D02*
X991300D01*
X989000Y1663802D01*
G01X1004307Y1676102D02*
X992598D01*
X989900Y1678800D01*
G01X1129963Y-139897D02*
Y-219897D01*
G01X1157963Y-123897D02*
G02I-12000J0D01*
G01X1152813D02*
G02I-6850J0D01*
G01X1145963Y-139897D02*
Y-107897D01*
G01X1161963Y-123897D02*
X1129963D01*
G54D12*
G01X11060Y227184D02*
X22133D01*
G01X11060Y238995D02*
X23895D01*
G01X11060Y246869D02*
X23869D01*
G01X11060Y1223247D02*
X22447D01*
G01X11060Y1211436D02*
X21064D01*
X23200Y1209300D01*
G01X11060Y1231121D02*
X22321D01*
G01X22133Y227184D02*
X23999Y229050D01*
G01X23869Y246869D02*
X24300Y247300D01*
X11999Y53550D03*
X11499Y34050D03*
X10000Y16500D03*
X11499Y142050D03*
X11999Y69050D03*
X6891Y161611D03*
X11302Y161500D03*
X7089Y166111D03*
X11500Y166000D03*
X9499Y301050D03*
Y281550D03*
X8999Y318550D03*
X8599Y751650D03*
X10999Y774050D03*
X8999Y889550D03*
X8499Y979050D03*
X8999Y961550D03*
Y942050D03*
Y926550D03*
X8499Y907050D03*
X8999Y1060550D03*
Y1041050D03*
Y1025550D03*
X8499Y1006050D03*
X8999Y988550D03*
X6500Y1098000D03*
Y1103500D03*
Y1110000D03*
Y1116500D03*
X8499Y1078050D03*
X6500Y1146000D03*
X13000Y1145500D03*
Y1151000D03*
X7000Y1151500D03*
X8799Y1302550D03*
X7499Y1282050D03*
X7999Y1264550D03*
X9399Y1347350D03*
X8299Y1320050D03*
X7099Y1717750D03*
X7199Y1731450D03*
X6099Y1753750D03*
X11299Y1850050D03*
X9099Y1881550D03*
X8503Y1956700D03*
X8499Y1979550D03*
X11500Y1987000D03*
X92999Y52050D03*
X90899Y14850D03*
X23499Y27050D03*
X50999Y21150D03*
Y47750D03*
X27799Y38450D03*
X25799Y64050D03*
X65499Y59050D03*
Y41550D03*
Y27050D03*
X40999Y42050D03*
Y27550D03*
X17600Y5604D03*
X36000D03*
X55700Y5900D03*
X73900Y6200D03*
X90900Y5800D03*
X88000Y36400D03*
X93000Y44900D03*
X92900Y39700D03*
X32400Y115400D03*
X37000Y115300D03*
X32300Y121000D03*
X36900Y120900D03*
X32100Y130700D03*
X37000D03*
X32100Y136600D03*
X36800Y136700D03*
X46499Y69050D03*
X52499Y145050D03*
Y130550D03*
X59499Y108050D03*
Y90550D03*
Y76050D03*
X96184Y151065D03*
X71015Y123666D03*
X78165Y137116D03*
X95814Y136065D03*
X77165Y110799D03*
X24000Y116500D03*
X36500Y179000D03*
Y188500D03*
X35000Y198500D03*
X30000Y179000D03*
X23500D03*
X30000Y188500D03*
X24000D03*
X29000Y198000D03*
X23500D03*
X15302Y161500D03*
X19500D03*
X15500Y166000D03*
X19198Y152000D03*
X19698Y166000D03*
X92899Y231450D03*
X48499Y228550D03*
X23999Y229050D03*
X52499Y162550D03*
X96184Y166065D03*
X23895Y238995D03*
X51099Y300050D03*
X90899Y309550D03*
X93199Y279650D03*
X84899Y289250D03*
X86899Y242750D03*
X75299Y261750D03*
X42999Y275650D03*
X48499Y260550D03*
Y243050D03*
X23999Y261050D03*
Y243550D03*
X52199Y342350D03*
X89899Y368350D03*
X94199Y325550D03*
X93499Y337450D03*
X95499Y355450D03*
X89999Y396450D03*
X39999Y359550D03*
Y342050D03*
Y327550D03*
X15499Y360050D03*
Y342550D03*
Y328050D03*
X94500Y456800D03*
X75300Y454100D03*
X67300Y450200D03*
X68899Y445450D03*
X87599Y403950D03*
X76099Y414250D03*
X95399Y416350D03*
X89099Y426150D03*
X93499Y481550D03*
Y477050D03*
X93199Y449850D03*
X93500Y445300D03*
X57300Y452700D03*
X68800Y454300D03*
X33799Y553050D03*
X37849Y561450D03*
X42299Y564150D03*
X62055Y561550D03*
X49555Y563550D03*
X75999Y556640D03*
X70800Y540300D03*
X77165Y514650D03*
X94499Y486550D03*
X66500Y543000D03*
X73000Y548700D03*
X31549Y566050D03*
X52333Y641295D03*
X72599Y578236D03*
X39999Y576550D03*
X61099Y603236D03*
X93599Y581236D03*
X92599Y606236D03*
X93100Y571640D03*
X32505Y592986D03*
X32300Y597800D03*
X35766Y602721D03*
X35157Y608117D03*
X44000Y728500D03*
X40000Y729000D03*
X56500Y724500D03*
X47800Y692800D03*
X53210Y701486D03*
X43499Y657550D03*
X43300Y806300D03*
X44500Y733000D03*
X40000D03*
X43999Y737550D03*
X39999Y738050D03*
X44499Y742050D03*
X39999D03*
X53999Y732050D03*
X53499Y739468D03*
X52299Y801450D03*
X39899Y754850D03*
X39399Y768750D03*
X27199Y764950D03*
X28599Y775450D03*
X26399Y750850D03*
X14799Y751450D03*
X17299Y773950D03*
X79900Y791300D03*
X67999Y790400D03*
X53999Y791000D03*
X59800Y812750D03*
X44899Y836250D03*
X96000Y866000D03*
X93299Y862050D03*
X54799Y838050D03*
X26799Y874550D03*
X26099Y891650D03*
X76399Y820450D03*
X70100Y818900D03*
X93690Y887139D03*
X93900Y882400D03*
X88999Y882550D03*
X90000Y854500D03*
X94001Y856895D03*
X93808Y852063D03*
X89499Y892050D03*
X93499D03*
X50399Y841450D03*
X54000Y819900D03*
X55299Y844350D03*
X61600Y850531D03*
X47200Y848431D03*
X43600Y883700D03*
X25699Y916150D03*
X25099Y942150D03*
X23899Y957950D03*
X93499Y897152D03*
X93000Y907165D03*
X77499Y921550D03*
X77002Y952079D03*
X76711Y948089D03*
X77499Y962152D03*
X83988Y934028D03*
X72300Y1018000D03*
X66000Y1020350D03*
X88005Y996217D03*
X93500Y1000300D03*
X24799Y992250D03*
X33899Y1005950D03*
X65799Y994050D03*
X72799Y982950D03*
X86900Y981600D03*
X70199Y1025050D03*
X79600Y1019100D03*
X67000Y1011500D03*
X21500Y1122500D03*
Y1092500D03*
X17500D03*
X14900Y1086100D03*
X22500Y1183000D03*
Y1176500D03*
Y1170000D03*
Y1164500D03*
X18000Y1145500D03*
X17500Y1150500D03*
X22447Y1223247D03*
X23200Y1209300D03*
X21299Y1300250D03*
X21799Y1282750D03*
X22321Y1231121D03*
X18099Y1343550D03*
X96000Y1369000D03*
X96100Y1384650D03*
X77166Y1353400D03*
X93316Y1351000D03*
X77165Y1327335D03*
X74600Y1557500D03*
X85000Y1536450D03*
X41325Y1548747D03*
X91399Y1549550D03*
X76499Y1507050D03*
Y1498050D03*
Y1512050D03*
Y1503050D03*
X76999Y1528050D03*
Y1519050D03*
X81999Y1541550D03*
X72599Y1546650D03*
X70099Y1540550D03*
X60000Y1535500D03*
X78400Y1566400D03*
X73500Y1613000D03*
X56500Y1596500D03*
X83499Y1602050D03*
X92499Y1589050D03*
X86999D03*
X83499Y1594050D03*
Y1598050D03*
X74999Y1602050D03*
X78999D03*
X81499Y1589050D03*
X78999Y1593550D03*
X74999Y1598050D03*
Y1593550D03*
X78999Y1598050D03*
X90999Y1628550D03*
Y1624550D03*
X91121Y1632549D03*
X86299Y1632550D03*
X85999Y1628550D03*
Y1624550D03*
X49000Y1585500D03*
X78462Y1574918D03*
X60700Y1578962D03*
X37173Y1583074D03*
X40200Y1586800D03*
X93999Y1669550D03*
X15299Y1723450D03*
X15399Y1708350D03*
X89999Y1703050D03*
X68000Y1701000D03*
X14899Y1736250D03*
X15299Y1753250D03*
X84099Y1737150D03*
X83599Y1744750D03*
X77165Y1759550D03*
X93499D03*
X94336Y1773113D03*
X78529Y1788113D03*
X62399Y1776050D03*
X91499Y1805549D03*
X62300Y1789650D03*
X68999Y1773550D03*
X38600Y1880200D03*
X31400Y1885200D03*
X30400Y1849650D03*
X23999Y1857950D03*
X27199Y1874350D03*
X52999Y1871550D03*
X57499Y1871050D03*
X40299Y1828750D03*
X50199Y1836052D03*
X49616Y1842667D03*
X94000Y1882500D03*
X82999Y1887550D03*
X78999D03*
X89200Y1832000D03*
X45900Y1862900D03*
X36100Y1892200D03*
X37499Y1967749D03*
X58999Y1958050D03*
X82499Y1957050D03*
X73499D03*
X66499D03*
X92499Y1959050D03*
X32999Y1964549D03*
Y1956855D03*
X17455Y1928781D03*
X82400Y1931500D03*
X69100Y1918800D03*
X54800Y1929400D03*
X47499Y1915050D03*
X62999Y1914550D03*
Y1926050D03*
X81499Y1915550D03*
X47499Y1930550D03*
X62499Y1939550D03*
X73499Y1945550D03*
X83999Y1945050D03*
X35521Y1930528D03*
X23999Y1932849D03*
X66900Y1891300D03*
X47999Y1891050D03*
X78999Y1891550D03*
X82999D03*
X78999Y1896050D03*
X78433Y1900010D03*
X78999Y1904050D03*
X83499Y1896050D03*
X83433Y1904010D03*
X83999Y1900050D03*
X79500Y1987500D03*
X61500D03*
X44500Y1987000D03*
X26500D03*
X55999Y1982550D03*
X96999Y49550D03*
X157299Y5150D03*
X107000Y6000D03*
X97800Y36000D03*
X96900Y40400D03*
X111300Y61900D03*
X178500Y63700D03*
X153700Y52700D03*
X167499Y43550D03*
X116400Y56000D03*
X129100Y55900D03*
X127499Y65050D03*
X141999Y65550D03*
X156499Y66050D03*
X169300Y130300D03*
X178700Y129900D03*
X152999Y141050D03*
X123499Y149050D03*
X133999D03*
X142999Y141050D03*
X132999Y141550D03*
X176499Y140050D03*
X167499Y149550D03*
X144499Y149050D03*
X163499Y140050D03*
X160999Y149550D03*
X123499Y140050D03*
X147500Y109900D03*
X136500Y92400D03*
X129999Y78050D03*
X166999Y88050D03*
X166499Y83550D03*
Y79050D03*
X158499D03*
Y84050D03*
Y88550D03*
Y93550D03*
X166999Y92550D03*
Y97050D03*
X127999Y99550D03*
X165499Y106050D03*
X169999Y103050D03*
X114800Y68500D03*
X177899Y199250D03*
X117500Y162300D03*
X124300Y167800D03*
X131799Y201950D03*
X142688Y218861D03*
X143110Y203861D03*
X97999Y199050D03*
X155999Y181050D03*
X156817Y165883D03*
X149400Y162500D03*
X135399Y277050D03*
X130799Y300250D03*
X158999Y259800D03*
X152808Y246341D03*
X166800Y240800D03*
X133000Y240500D03*
X157740Y273924D03*
X139399Y372350D03*
X167299Y369350D03*
X130099Y326150D03*
X134699Y356050D03*
X126099Y396150D03*
X152499Y395950D03*
X137100Y436800D03*
X129400Y426900D03*
X144999Y425550D03*
X135999Y472550D03*
X135140Y478930D03*
X100500Y456700D03*
X99399Y437450D03*
X124899Y409050D03*
X133499Y445050D03*
X128999Y445550D03*
X130000Y452000D03*
X97699Y477050D03*
Y481550D03*
X149700Y471600D03*
X154100Y476500D03*
X164600Y476700D03*
X171300D03*
X97999Y445550D03*
X97699Y449850D03*
X147300Y526700D03*
X147590Y521500D03*
X108599Y557236D03*
X154099Y529236D03*
X101500Y536500D03*
X139200Y484300D03*
X134499Y488050D03*
X132349Y509050D03*
X145649Y509550D03*
X136349Y509050D03*
X98999Y488050D03*
X157499Y502550D03*
X140499Y499050D03*
X153499Y502550D03*
X148999D03*
X136299Y499050D03*
X123999Y495050D03*
X134700Y553800D03*
X108900Y587600D03*
X162500Y623400D03*
X140000Y587700D03*
X140499Y600550D03*
X152400Y643300D03*
X140499Y626050D03*
X143999Y605550D03*
X153000Y574000D03*
X137100Y570500D03*
X160900Y573000D03*
X170799Y689150D03*
X171999Y672450D03*
X131099Y700450D03*
X139099Y707150D03*
X152124Y651868D03*
X159054Y665400D03*
X152499Y810550D03*
X110800Y772700D03*
X178899Y765250D03*
X172599Y774250D03*
X161999Y768050D03*
X152499Y816050D03*
Y820550D03*
Y825050D03*
X156499Y876050D03*
Y870550D03*
X97499Y862050D03*
X111299Y821050D03*
X172099Y877450D03*
X168499Y846713D03*
X173899Y846550D03*
X161999Y843550D03*
Y848050D03*
X156499Y846050D03*
X156999Y850050D03*
X158114Y883290D03*
X156499Y886950D03*
X155499Y891050D03*
Y896050D03*
X97700Y887400D03*
X97900Y882400D03*
X163999Y863050D03*
X159999D03*
X155999Y859050D03*
Y863050D03*
X97800Y851800D03*
X98001Y856950D03*
X97499Y892550D03*
X151999Y936550D03*
X152499Y931550D03*
X109500Y901100D03*
X153299Y943750D03*
X106500Y943000D03*
X105300Y960300D03*
X169299Y956350D03*
X159459Y896616D03*
X163499Y896550D03*
X157499Y909050D03*
Y904550D03*
X159186Y946117D03*
X151300Y1049300D03*
X171499Y998650D03*
X156499Y985950D03*
X149499Y997650D03*
X162499Y1023550D03*
X163499Y1035050D03*
X158300Y1015000D03*
X141234Y1029885D03*
X140864Y1044885D03*
X159499Y1044579D03*
X165600Y1057428D03*
X99200Y994200D03*
X103900Y999400D03*
X109499Y1080550D03*
X111140Y1074659D03*
X100999Y1099550D03*
X105000Y1100500D03*
X100999Y1095050D03*
X105006Y1095366D03*
X110999Y1130550D03*
X115200Y1130300D03*
X110999Y1126050D03*
Y1122050D03*
Y1118050D03*
X114999Y1126050D03*
Y1122050D03*
Y1118050D03*
X137900Y1103400D03*
X139100Y1097100D03*
X169299Y1067150D03*
X168099Y1083550D03*
X167999Y1092850D03*
X143200Y1116300D03*
X134500Y1108100D03*
X171599Y1139950D03*
X167499Y1118550D03*
X167999Y1130550D03*
X133200Y1132100D03*
X164999Y1075550D03*
X159055Y1070400D03*
X106999Y1114960D03*
X120982Y1099733D03*
X109499Y1098350D03*
X144149Y1226113D03*
Y1222113D03*
X148499D03*
Y1226113D03*
X145900Y1163200D03*
X163499Y1171650D03*
X151699Y1158550D03*
X144399Y1171150D03*
X150999Y1181150D03*
X141499Y1185550D03*
X151499Y1173050D03*
X121657Y1224604D03*
X120999Y1188050D03*
X111999D03*
X102999D03*
X128400Y1188600D03*
X104999Y1265050D03*
X144149Y1230113D03*
X148486D03*
X113999Y1285550D03*
X104999Y1231050D03*
X100999Y1231032D03*
X120999Y1228550D03*
X120499Y1264550D03*
X126499D03*
X123938Y1267623D03*
X103499Y1305050D03*
X117149Y1267550D03*
X105499Y1292550D03*
X175823Y1297070D03*
X175499Y1302113D03*
Y1306113D03*
Y1292550D03*
X145999Y1353050D03*
X167499Y1389050D03*
X123500Y1360300D03*
X136783Y1335517D03*
X143500Y1323500D03*
X156999Y1397750D03*
X143199Y1412050D03*
X163499Y1433350D03*
X166799Y1409350D03*
X178200Y1393400D03*
X176599Y1447450D03*
X172299Y1465850D03*
X165499Y1453550D03*
X157915Y1420460D03*
X140799Y1435460D03*
X166799Y1487450D03*
X176299Y1500150D03*
X159054Y1476200D03*
X124999Y1616050D03*
Y1620050D03*
Y1629050D03*
Y1633050D03*
X119999Y1629050D03*
X120100Y1633100D03*
X131599Y1714150D03*
X105749Y1712749D03*
X122499Y1668550D03*
Y1672550D03*
X126562Y1670613D03*
X118999Y1670550D03*
X116499Y1716750D03*
X135899Y1722550D03*
X118499Y1697750D03*
X127499Y1708250D03*
X172499Y1714050D03*
X167499Y1714113D03*
X162499D03*
X130499Y1730050D03*
X128000Y1735000D03*
X144499Y1729550D03*
X139500Y1730500D03*
X133000Y1734500D03*
X157500Y1797400D03*
X126599Y1789650D03*
X120299Y1796150D03*
X142144Y1801644D03*
X104417Y1791480D03*
X144499Y1745550D03*
X137999Y1747723D03*
X129999Y1747050D03*
X123499D03*
X117499Y1745050D03*
X121151Y1805128D03*
X170499Y1731050D03*
X165499Y1730613D03*
X172499Y1726613D03*
X167999D03*
X163499D03*
X97999Y1815050D03*
X104500Y1813400D03*
X173899Y1813250D03*
X177599Y1866750D03*
X168299Y1879850D03*
X168499Y1855550D03*
X127499Y1889050D03*
X126999Y1882550D03*
X111499Y1877550D03*
Y1882550D03*
X122999Y1883050D03*
X115999Y1882550D03*
X157999Y1840972D03*
X158000Y1825400D03*
X159054Y1881800D03*
X167200Y1868000D03*
X159054Y1855050D03*
X143491Y1856400D03*
X116499Y1877550D03*
X122999Y1889050D03*
X103920Y1833104D03*
X132700Y1972400D03*
X137900Y1972200D03*
X126500Y1972400D03*
X168899Y1960750D03*
X163599Y1892050D03*
X159173Y1935972D03*
X142499Y1905972D03*
X141499Y1895972D03*
X115100Y1932000D03*
X131100Y1908500D03*
X129600Y1912400D03*
X124433Y1908510D03*
X124999Y1912550D03*
X98433Y1940510D03*
X98999Y1944550D03*
X102433Y1940555D03*
X103433Y1944510D03*
X132700Y1978600D03*
X137900Y1978400D03*
X126600Y1978500D03*
X119999Y1978550D03*
X119499Y1972550D03*
X98000Y1987500D03*
X163500D03*
X146000D03*
X128500D03*
X115000Y1987000D03*
X189499Y39150D03*
X197999Y39900D03*
X193999D03*
X208499Y45650D03*
X199999Y46050D03*
X194499Y44050D03*
X246200Y65800D03*
X246000Y61300D03*
Y56500D03*
Y52100D03*
X245600Y43800D03*
X245500Y39100D03*
X247100Y47900D03*
X189499Y4550D03*
X206999Y5050D03*
X226499D03*
X241999D03*
X261499Y4550D03*
X231600Y63700D03*
X230200Y39100D03*
X220900Y38800D03*
X225499Y52550D03*
Y46550D03*
Y63550D03*
Y58050D03*
X183499Y45550D03*
X192499Y57550D03*
X246000Y70800D03*
X244900Y149100D03*
X244499Y136550D03*
Y122050D03*
X195499Y99050D03*
X204499Y116550D03*
X241099Y95050D03*
X194499Y109350D03*
X178999Y88550D03*
X229099Y161350D03*
X206899Y171650D03*
X190199Y178650D03*
X232400Y220700D03*
X210999Y221550D03*
X191999D03*
X227499Y192050D03*
X231999D03*
X227999Y187050D03*
X231999D03*
X227999Y182550D03*
X231999D03*
X227999Y178050D03*
X231999D03*
X249800Y248800D03*
X235399Y263350D03*
X201199Y266750D03*
X181299Y267350D03*
X217999Y250550D03*
X203499D03*
X185999D03*
X187199Y359050D03*
X223799Y365350D03*
X209199Y365050D03*
X181599Y396250D03*
X217599Y396450D03*
X258999Y396650D03*
X179999Y442550D03*
X179649Y438550D03*
X183999D03*
Y442550D03*
Y447050D03*
X179999D03*
X209999Y426150D03*
X237699Y426050D03*
X218499Y474850D03*
X251499Y446050D03*
X231999Y445550D03*
X251999Y462050D03*
X232499Y461550D03*
X209499Y412550D03*
X220000Y421000D03*
X232999Y414550D03*
X252499Y415050D03*
X194999Y490050D03*
X190499Y487550D03*
X191199Y491550D03*
X244199Y483350D03*
X224299Y494650D03*
X242099Y511750D03*
X244999Y559550D03*
Y545050D03*
X220499Y560050D03*
Y545550D03*
X257499Y530050D03*
Y512550D03*
Y498050D03*
X205300Y508100D03*
X190499Y507513D03*
X184200Y484400D03*
X187499Y531613D03*
Y536113D03*
X193499Y541113D03*
X188999D03*
X193499Y549613D03*
X188999D03*
Y545613D03*
X193999Y545550D03*
X257199Y640050D03*
X224999Y613450D03*
X256499Y609050D03*
Y591550D03*
Y577050D03*
X245000Y647000D03*
X244499Y632050D03*
X219999Y647050D03*
Y632550D03*
X207300Y639400D03*
X206499Y623550D03*
Y609050D03*
X181999Y641550D03*
Y624050D03*
Y609550D03*
X244999Y577050D03*
X220499Y577550D03*
X199199Y659150D03*
X234200Y668300D03*
X226399Y677550D03*
X212999Y677350D03*
X190399Y689050D03*
X182599Y688350D03*
X246500Y663300D03*
X218800Y668700D03*
X224099Y770250D03*
X209500Y759000D03*
X208799Y766750D03*
X214799Y774750D03*
X245599Y773450D03*
X234299Y773750D03*
X247099Y795050D03*
X227199D03*
X197099D03*
X254699Y807650D03*
X233799Y806350D03*
X208299Y805350D03*
X198199Y805950D03*
X190699Y778350D03*
X215999Y887550D03*
X220499D03*
X215499Y883550D03*
X204496Y846111D03*
X204649Y838050D03*
X208999D03*
X209000Y846113D03*
X204649Y842113D03*
X208986D03*
X244099Y857450D03*
X245199Y878050D03*
X232399Y886550D03*
X252899Y886350D03*
X252399Y838250D03*
X245399Y823550D03*
X217300Y816800D03*
X198499Y884113D03*
X215500Y893610D03*
X245399Y907450D03*
X243899Y923650D03*
X242199Y938750D03*
X256199Y916250D03*
X254899Y929250D03*
X253499Y938050D03*
X252499Y948850D03*
X244199Y973250D03*
X225299Y957650D03*
X213999Y958650D03*
X206699Y953050D03*
X203999Y943350D03*
X204699Y929450D03*
X205999Y978250D03*
X256499Y967050D03*
X233499Y966050D03*
X216999Y967550D03*
X204699Y896610D03*
X219499Y939613D03*
Y948613D03*
Y943813D03*
X214999Y939613D03*
Y944113D03*
Y948613D03*
X219499Y926613D03*
X214999D03*
X254499Y984550D03*
X245899Y995250D03*
X232299Y981950D03*
X206299Y990250D03*
X207299Y1008150D03*
X202100Y1028100D03*
X253999Y1052050D03*
X253499Y1038550D03*
X232499Y1038050D03*
X216499Y1053050D03*
X215999Y1039550D03*
X258999Y1011550D03*
X233999Y1012550D03*
Y997050D03*
X217999Y1012050D03*
X217499Y998550D03*
Y981050D03*
X199499Y1093850D03*
X209900Y1093600D03*
X249499Y1104150D03*
X260349Y1139200D03*
X229800Y1077300D03*
X242000Y1069700D03*
X214499Y1154250D03*
X223099Y1182750D03*
X210199Y1173450D03*
X204199Y1163850D03*
X208199Y1145850D03*
X180400Y1202800D03*
X201600Y1205900D03*
X220999Y1224350D03*
X242199Y1210050D03*
X242599Y1198350D03*
X232599Y1195750D03*
X247899Y1208650D03*
X251999Y1184550D03*
X212499Y1212550D03*
X181700Y1219900D03*
X212499Y1184550D03*
X196499Y1224550D03*
Y1215550D03*
Y1196550D03*
X259999Y1152992D03*
X259499Y1161550D03*
X202199Y1276850D03*
X202899Y1291450D03*
X179500Y1262000D03*
X179800Y1244100D03*
X196399Y1236650D03*
X221599Y1237250D03*
X222299Y1251850D03*
X229899Y1250550D03*
X216300Y1274800D03*
X234299Y1232650D03*
X261199Y1227950D03*
X250900Y1248500D03*
X242900Y1263000D03*
X232799Y1276150D03*
X254899Y1289950D03*
X241399Y1303250D03*
X211499Y1267050D03*
Y1258050D03*
Y1239050D03*
X195499Y1279050D03*
Y1270050D03*
Y1251050D03*
X179999Y1306050D03*
Y1301550D03*
Y1292550D03*
Y1296613D03*
X239099Y1314150D03*
X252399Y1326350D03*
X219099Y1325950D03*
X226599Y1340250D03*
X207699Y1337950D03*
X195500Y1352500D03*
X213199Y1350050D03*
X227399Y1363050D03*
X234300Y1375700D03*
X217499Y1387450D03*
X249800Y1388400D03*
X245999Y1358050D03*
X246499Y1370050D03*
X245999Y1339050D03*
X208049Y1385550D03*
X181000Y1361000D03*
X180400Y1374000D03*
X258999Y1396950D03*
X230599Y1400250D03*
X217999Y1408850D03*
X204699Y1418350D03*
X203199Y1393250D03*
X201000Y1408500D03*
X180599Y1424050D03*
X180000Y1439500D03*
X204999Y1472650D03*
X250199Y1473550D03*
X226300Y1447800D03*
X230899Y1437350D03*
X238899Y1453750D03*
X259299Y1438750D03*
X227999Y1421550D03*
X212400Y1433700D03*
X194200Y1457900D03*
X244999Y1412550D03*
X245499Y1424550D03*
X223029Y1465580D03*
X221199Y1556050D03*
X181500Y1479000D03*
X202399Y1500750D03*
X208999Y1491250D03*
X247500Y1499000D03*
X248000Y1482000D03*
X212899Y1535550D03*
X230999D03*
X213399Y1500300D03*
X236999Y1535550D03*
X260999Y1503550D03*
X180299Y1626550D03*
X180000Y1619600D03*
X195700Y1619100D03*
X195600Y1623700D03*
X180299Y1634550D03*
X179733Y1630590D03*
X225499Y1606050D03*
X246200Y1617600D03*
X239400Y1624300D03*
X218000Y1614300D03*
X209200Y1624000D03*
X228999Y1637550D03*
X211999Y1568550D03*
X238300Y1575100D03*
X231499Y1575050D03*
X224499D03*
X217999Y1574550D03*
X211999D03*
X258700Y1645100D03*
X237400Y1663800D03*
X230600Y1670500D03*
X197600Y1694900D03*
X204400Y1688200D03*
X216601Y1684350D03*
X226800Y1684200D03*
X220100Y1691700D03*
X209901Y1691850D03*
X212000Y1701300D03*
X201801Y1701450D03*
X195001Y1708150D03*
X205200Y1708000D03*
X180701Y1716050D03*
X195500Y1717000D03*
X200600Y1663600D03*
X199900Y1670600D03*
X213000Y1672500D03*
X181900Y1675300D03*
X255699Y1722550D03*
X222700Y1710100D03*
X242999Y1658050D03*
X193499Y1674050D03*
X253999Y1676550D03*
X235499Y1697050D03*
X256499Y1710050D03*
X180000Y1731000D03*
X179701Y1724550D03*
X195000Y1725500D03*
X249199Y1743150D03*
X222499Y1743850D03*
X259499Y1760650D03*
X221499Y1760950D03*
X199699Y1761450D03*
X220799Y1791550D03*
X252199Y1793050D03*
X238699Y1801850D03*
X205199Y1801950D03*
X182299Y1801350D03*
X206900Y1726700D03*
X185999Y1746050D03*
X237999Y1730550D03*
X244999Y1755050D03*
X195499Y1852550D03*
X253899Y1813250D03*
X215299Y1813950D03*
X255999Y1855950D03*
X204399Y1855450D03*
X206999Y1867550D03*
X241199Y1867150D03*
X244700Y1878700D03*
X224800Y1867000D03*
X212399Y1885850D03*
X199599Y1879850D03*
X181099Y1885850D03*
X261499Y1825050D03*
X209999D03*
X192100Y1813500D03*
X228999Y1856050D03*
X247252Y1826803D03*
X229800Y1872000D03*
X218100Y1882700D03*
X215999Y1955050D03*
X249499Y1924350D03*
X231999Y1918050D03*
X210999Y1945750D03*
X226999Y1941050D03*
X241255Y1896055D03*
X205499Y1968650D03*
X183999Y1968150D03*
X190399Y1961250D03*
X207199Y1892850D03*
X191599Y1891550D03*
X238999Y1970550D03*
X232999Y1971050D03*
X227499D03*
X221300Y1971200D03*
X214999Y1914050D03*
X240900Y1979000D03*
X225199Y1978750D03*
X209699D03*
X188199Y1978250D03*
X254500Y1987500D03*
X236500D03*
X216999Y1987550D03*
X199000Y1987500D03*
X183000D03*
X199600Y1974900D03*
X289499Y39050D03*
X286603Y34928D03*
X278999Y5050D03*
X292999Y4550D03*
X310499Y5050D03*
X329999D03*
X306999Y55450D03*
X311299D03*
X315799Y55350D03*
X337799Y67110D03*
X290999Y67550D03*
X300700Y39400D03*
X304800Y29200D03*
X304500Y44500D03*
X305100Y39700D03*
X294100Y28000D03*
X308900Y41000D03*
X308800Y46400D03*
X306100Y126500D03*
X332200Y94200D03*
X283599Y106250D03*
X274700Y131500D03*
X280999Y120050D03*
X285999Y72550D03*
X289999D03*
X288499Y76550D03*
X289499Y80550D03*
X312499Y72550D03*
X308499D03*
X303999Y74050D03*
X307999Y78550D03*
X338499Y120550D03*
X315800Y104200D03*
X324800Y93100D03*
X342999Y169050D03*
X343799Y204550D03*
X321799Y173950D03*
X343399Y161350D03*
X307199Y205550D03*
X317499Y192950D03*
X331499Y193250D03*
X262699Y208550D03*
X262299Y164050D03*
X280999Y152050D03*
X343999Y190050D03*
X337999Y219050D03*
X310499Y216550D03*
X290999Y216050D03*
X271999D03*
X325499Y249450D03*
X313199Y270350D03*
X297999Y245050D03*
X283499D03*
X265999D03*
X343499Y253550D03*
X337499Y282550D03*
X313000Y313900D03*
X316999Y312576D03*
X279998Y308614D03*
Y304114D03*
Y299614D03*
Y295114D03*
X267498Y310114D03*
Y305114D03*
Y300114D03*
Y295114D03*
X323499Y331550D03*
X305998Y352114D03*
X293998Y361114D03*
Y356614D03*
Y352114D03*
X289998Y361114D03*
Y356614D03*
Y352114D03*
X284999Y342750D03*
X276299Y376050D03*
X299899Y376650D03*
X328799Y372350D03*
X339399Y358050D03*
X289399Y395750D03*
X310999Y396250D03*
X338399Y395650D03*
X321748Y343299D03*
X277799Y338599D03*
X280345Y328896D03*
X266699Y425050D03*
X336099Y417550D03*
X322099Y426850D03*
X338899Y433850D03*
X300899Y431850D03*
X328599Y442250D03*
X291599Y446150D03*
X266199Y472350D03*
X327900Y463200D03*
X306100Y462000D03*
X286999Y462050D03*
X272499Y445050D03*
X272999Y461050D03*
X269999Y415050D03*
X284499D03*
X303999Y415550D03*
X324999Y414550D03*
X277999Y545350D03*
X329999Y510450D03*
X298599Y501250D03*
X309399Y513450D03*
X321999Y533150D03*
X297599Y519350D03*
X340799Y512050D03*
X341399Y535850D03*
Y558950D03*
X331999Y555050D03*
Y540550D03*
X307499Y555550D03*
Y541050D03*
X281999Y529550D03*
Y512050D03*
Y497550D03*
X321999Y550550D03*
X297499Y551050D03*
X333499Y483050D03*
X312499Y484050D03*
X292999Y483550D03*
X321299Y565250D03*
X296199Y568550D03*
X320799Y582050D03*
X340299Y586550D03*
X342199Y613050D03*
X328599Y602450D03*
X302899Y607950D03*
X328499Y635650D03*
X317999Y627850D03*
X342099Y646350D03*
X280999Y608550D03*
Y591050D03*
Y576550D03*
X331999Y572550D03*
X307499Y573050D03*
X331999Y646550D03*
X307499Y647050D03*
X293999Y630550D03*
Y616050D03*
X269499Y631050D03*
Y616550D03*
X341899Y664950D03*
X342599Y678850D03*
X341399Y715050D03*
X330799Y712450D03*
X324599Y696150D03*
X297699Y681850D03*
X296399Y716950D03*
X308899Y705150D03*
X298399Y703450D03*
X331999Y678550D03*
Y661050D03*
X307499Y679050D03*
Y661550D03*
X293999Y648050D03*
X269499Y648550D03*
X268499Y716550D03*
Y711550D03*
Y701550D03*
Y706550D03*
X280999Y717550D03*
X280433Y713590D03*
X280999Y701550D03*
Y705550D03*
X331263Y742294D03*
X285264Y749050D03*
X294999Y767050D03*
X290999D03*
X294999Y762550D03*
Y758050D03*
X290999Y762550D03*
Y758050D03*
X306999D03*
X338099Y811650D03*
X307999Y803150D03*
X307899Y794550D03*
X287799Y794850D03*
X268099Y795450D03*
X275299Y806350D03*
X315000Y754500D03*
X284764Y738315D03*
X338599Y821650D03*
X318999Y814350D03*
X338599Y840450D03*
X325599Y823950D03*
X283599Y857450D03*
X293899Y843850D03*
X304899Y856150D03*
X315199Y869450D03*
X323099Y885050D03*
X340099Y887350D03*
X330299Y871850D03*
X323799Y859850D03*
X313499Y847850D03*
X300199Y835250D03*
X288899Y820550D03*
X264999Y858450D03*
X280999Y843050D03*
Y827550D03*
X264999Y842550D03*
X264499Y829050D03*
X297499Y884050D03*
Y868550D03*
X281499Y883550D03*
X280999Y870050D03*
X295999Y948550D03*
X265799Y901850D03*
X274299Y912950D03*
X310699Y943550D03*
X323499Y956950D03*
X329799Y970650D03*
X331099Y923650D03*
X322099Y913650D03*
X302499Y899050D03*
X321099Y899650D03*
X338399Y901050D03*
X340099Y910350D03*
X340399Y931250D03*
X340099Y952850D03*
X328099Y937250D03*
X315199Y925950D03*
X302199Y914650D03*
X287299Y901050D03*
X269599Y923950D03*
X267199Y935350D03*
X264799Y946850D03*
X263299Y959350D03*
X281099Y943550D03*
X278799Y956150D03*
X277599Y975250D03*
X290099Y948650D03*
X289399Y963350D03*
X288099Y971250D03*
X299399Y965950D03*
X298099Y977250D03*
X307999Y970650D03*
X272999Y965550D03*
X333099Y983450D03*
X285399Y982950D03*
X294699Y989550D03*
X306699Y981250D03*
X304399Y997550D03*
X320999Y997250D03*
X331299Y1017150D03*
X331599Y1028750D03*
X329599Y1040750D03*
X321299Y1012450D03*
Y1024750D03*
X318299Y1038750D03*
X329599Y1057050D03*
X317699Y1054650D03*
X299999Y1052350D03*
X289699Y1021750D03*
X298399Y1008150D03*
X287099Y1000150D03*
X306399Y1020750D03*
X303699Y1038050D03*
X304699Y1057050D03*
X287099Y1035050D03*
X275099Y1024750D03*
X262499Y995850D03*
X269999Y1052550D03*
Y1037050D03*
X274999Y1012050D03*
Y996550D03*
X272999Y981050D03*
X339599Y1081550D03*
X319999Y1066950D03*
X274900Y1115600D03*
X262499Y1129150D03*
X272999Y1102850D03*
X312299Y1093550D03*
X276299Y1134550D03*
X290699Y1122650D03*
X329299Y1098550D03*
X326599Y1112350D03*
X307999Y1142050D03*
X299499Y1113550D03*
Y1098050D03*
X283499Y1113050D03*
X282999Y1099550D03*
X332999Y1138550D03*
Y1123050D03*
X317999Y1137550D03*
X316499Y1124550D03*
X283299Y1144850D03*
X323999Y1153250D03*
X304499Y1156650D03*
X313499Y1170150D03*
X291399Y1174150D03*
X300699Y1185150D03*
X279799Y1191750D03*
X286599Y1203750D03*
X315408Y1202663D03*
X329799Y1182750D03*
X311999Y1213850D03*
X300699Y1227350D03*
X272999Y1214150D03*
X326649Y1218850D03*
X328999Y1200550D03*
X272499Y1153050D03*
X268499D03*
X263999D03*
X271999Y1161550D03*
X267999D03*
X263499D03*
X333349Y1307000D03*
X310299Y1240050D03*
X264800Y1261300D03*
X283799Y1249250D03*
X304699Y1265850D03*
X312499Y1280350D03*
X300499Y1305350D03*
X274299Y1276450D03*
X295399Y1292950D03*
X281099Y1302850D03*
X333349Y1288900D03*
Y1270500D03*
X327999Y1255050D03*
X326649Y1227850D03*
X333349Y1332800D03*
X311500Y1316300D03*
X264799Y1313850D03*
X286799Y1326450D03*
X297899Y1336150D03*
X298099Y1357250D03*
X265299Y1339650D03*
X263699Y1359550D03*
X301699Y1377950D03*
X278799Y1386250D03*
X265499Y1376950D03*
X343599Y1360050D03*
X344399Y1338150D03*
X313600Y1391300D03*
X312900Y1366900D03*
X333349Y1363500D03*
X311900Y1344900D03*
X286499Y1364050D03*
Y1345050D03*
X301699Y1395750D03*
X268499Y1453550D03*
X278000Y1422000D03*
X270599Y1408550D03*
X303499Y1411250D03*
X300899Y1433350D03*
X286600Y1449700D03*
X304699Y1457550D03*
X344099Y1449550D03*
Y1421150D03*
Y1393750D03*
X313600Y1442700D03*
X312800Y1467400D03*
X333349Y1429500D03*
X312100Y1420700D03*
X285499Y1418550D03*
Y1427550D03*
Y1399550D03*
X333349Y1393100D03*
X286868Y1557582D03*
X333349Y1481900D03*
X332500Y1519700D03*
X296599Y1497150D03*
X312000Y1514600D03*
X286700Y1516100D03*
X290411Y1546462D03*
X267349Y1518150D03*
Y1522550D03*
X266999Y1512550D03*
X267349Y1527172D03*
X279499Y1510550D03*
Y1515050D03*
X279075Y1525957D03*
X278567Y1529925D03*
X305998Y1569114D03*
X293998Y1578114D03*
Y1573614D03*
Y1569114D03*
X289998Y1578114D03*
Y1573614D03*
Y1569114D03*
X307000Y1619600D03*
X344500Y1583600D03*
X337199Y1636350D03*
X278499Y1621550D03*
X265700Y1635100D03*
X289000Y1641800D03*
X320299Y1642950D03*
X316799Y1657450D03*
X302399Y1662950D03*
X284300Y1676900D03*
X334399Y1691650D03*
X329999Y1716950D03*
X291099Y1707450D03*
X335767Y1662735D03*
X318499Y1675550D03*
X299999Y1696050D03*
X270999Y1660550D03*
X273499Y1694050D03*
X280499Y1718550D03*
X320999Y1706050D03*
X303999Y1722050D03*
X343899Y1752650D03*
X297099Y1733850D03*
X270599Y1748950D03*
X290699Y1760750D03*
X286599Y1791850D03*
X327299D03*
X322299Y1802150D03*
X303999Y1800850D03*
X270599Y1801450D03*
X263499Y1734550D03*
X285499Y1742550D03*
X321999Y1733050D03*
X303499Y1753550D03*
X321499Y1772550D03*
X334999Y1797050D03*
X326301Y1766030D03*
X299995Y1810554D03*
X315499Y1812250D03*
X284299Y1811150D03*
X270299Y1867250D03*
X337499Y1855950D03*
X316999D03*
X298999D03*
X308099Y1880550D03*
X295299Y1870250D03*
X313599Y1889250D03*
Y1870250D03*
X326399Y1876250D03*
X336799Y1888950D03*
Y1869950D03*
X283999Y1856050D03*
X264499Y1968050D03*
X331499Y1940750D03*
X306999Y1932550D03*
X302499D03*
X298499D03*
X293999Y1933050D03*
X306000Y1961500D03*
X305500Y1965500D03*
X293999Y1971050D03*
Y1966550D03*
Y1962050D03*
X289499Y1961550D03*
Y1966550D03*
Y1971050D03*
X314099Y1901250D03*
X326899Y1907250D03*
X326399Y1895250D03*
X335799Y1916450D03*
X336799Y1897950D03*
X305999Y1913050D03*
X302499Y1922050D03*
X296858Y1956228D03*
X281999Y1918550D03*
Y1923550D03*
Y1928550D03*
X266999Y1915550D03*
Y1920050D03*
Y1924550D03*
Y1929050D03*
Y1933550D03*
X326799Y1977050D03*
X329999Y1987550D03*
X311500Y1987500D03*
X291499Y1987550D03*
X272000Y1987500D03*
X381499Y65550D03*
X376999D03*
X371999Y15550D03*
X376499D03*
X380999D03*
X369999Y23550D03*
Y19050D03*
X382499Y20050D03*
X385499Y59550D03*
X416999Y25050D03*
X417499Y46550D03*
X416999Y63550D03*
X345499Y5050D03*
X364999Y4550D03*
X382499Y5050D03*
X395999Y5550D03*
X413499Y6050D03*
X378428Y51119D03*
X347328Y31519D03*
X381499Y70050D03*
X376999D03*
X381299Y136750D03*
X389599Y90950D03*
X400499Y134050D03*
Y119550D03*
X363999Y136050D03*
X417499Y79050D03*
Y93550D03*
Y108050D03*
Y125550D03*
X416999Y145050D03*
X390411Y69638D03*
X360999Y113050D03*
X356499D03*
X351999D03*
X347499D03*
X360999Y100550D03*
X355999D03*
X350999D03*
X345999D03*
X387599Y220150D03*
X385999Y207250D03*
X354099Y175350D03*
X389299Y161650D03*
X400499Y151550D03*
X363999Y153550D03*
X369999Y219050D03*
X382499Y190550D03*
X355499Y219050D03*
X362999Y190050D03*
X416999Y164050D03*
X417999Y185050D03*
X423799Y259750D03*
X383299Y310250D03*
X386899Y299250D03*
X359399Y307250D03*
X347399Y301950D03*
X355999Y242750D03*
X347699Y269050D03*
X382999Y276650D03*
X412999Y307550D03*
Y290050D03*
Y275550D03*
X369499Y282550D03*
X381999Y254050D03*
X354999Y282550D03*
X362499Y253550D03*
X392999Y337050D03*
X354099Y373050D03*
X368299Y386350D03*
X357999Y359050D03*
X380599Y381050D03*
X386599Y348450D03*
X394899Y357750D03*
X422499Y348150D03*
X422199Y363350D03*
X420199Y391350D03*
X419599Y458550D03*
X426599Y415350D03*
X415099Y422550D03*
X410799Y431150D03*
X354699Y426650D03*
X356399Y451750D03*
X351399Y470750D03*
X358399Y498650D03*
X357399Y521250D03*
Y530550D03*
Y543850D03*
X357999Y559450D03*
X415999Y518550D03*
X420199Y638550D03*
X427499Y624550D03*
X359399Y576050D03*
Y599650D03*
X360399Y615550D03*
X359699Y627550D03*
X345399Y698950D03*
X358899Y657150D03*
X359399Y669450D03*
X359199Y690650D03*
X357699Y707750D03*
X353999Y787750D03*
X347699Y773450D03*
X355999Y752850D03*
X424999Y766550D03*
X422999Y785050D03*
Y799550D03*
X418799Y896050D03*
Y877050D03*
X422499Y855550D03*
Y836550D03*
X422999Y817050D03*
X374500Y973500D03*
X375000Y939000D03*
Y1034000D03*
X424299Y1034050D03*
X423299Y1013050D03*
Y994050D03*
X373500Y1089500D03*
X419999Y1115550D03*
X409499Y1102550D03*
X416099Y1183550D03*
X415499Y1176050D03*
Y1161550D03*
X419499Y1219550D03*
X377499Y1210050D03*
Y1201050D03*
Y1182050D03*
X420099Y1241550D03*
X419499Y1234050D03*
X376599Y1293950D03*
X376499Y1264550D03*
Y1255550D03*
Y1236550D03*
X424999Y1278550D03*
X425499Y1290550D03*
X424999Y1259550D03*
X420499Y1335550D03*
X416699Y1342650D03*
X416199Y1367550D03*
X375599Y1323350D03*
X374499Y1375550D03*
Y1366550D03*
Y1347550D03*
X423299Y1430350D03*
X426799Y1416050D03*
X422299Y1394950D03*
X425799Y1447950D03*
X427099Y1469150D03*
X376299Y1437650D03*
X373099Y1456550D03*
X373499Y1430050D03*
Y1421050D03*
Y1402050D03*
X414799Y1532350D03*
X424299Y1541350D03*
X374099Y1554550D03*
X374799Y1491250D03*
X380999Y1618050D03*
X415999Y1603250D03*
X416199Y1625250D03*
X425499Y1635050D03*
X418299Y1561250D03*
X351899Y1570850D03*
X350600Y1610900D03*
X349099Y1634550D03*
X376099Y1572850D03*
X375099Y1608250D03*
X377700Y1629000D03*
X414799Y1653750D03*
X414399Y1678350D03*
X414499Y1707250D03*
X374999Y1656750D03*
X377099Y1696350D03*
X380099Y1709650D03*
X351099Y1691150D03*
X352000Y1700400D03*
X427499Y1662050D03*
X417799Y1790850D03*
X387899Y1802850D03*
X359499Y1736850D03*
X376799Y1734050D03*
X393499Y1759550D03*
X376499Y1775550D03*
X357999Y1796050D03*
X410757Y1772872D03*
X393999Y1784550D03*
X422999Y1778550D03*
X414499Y1810450D03*
X355699Y1810750D03*
X426499Y1855450D03*
X406999Y1855950D03*
X391499D03*
X369499D03*
X351999Y1855450D03*
X359999Y1878550D03*
X421399Y1888050D03*
X369799Y1880050D03*
X389499Y1885050D03*
X348999Y1879050D03*
X406499Y1874050D03*
X367299Y1956950D03*
X358999Y1925050D03*
X359999Y1897550D03*
Y1906550D03*
X420399Y1962550D03*
Y1934550D03*
Y1953550D03*
X421399Y1916050D03*
Y1907050D03*
X347699Y1972250D03*
X367999Y1940250D03*
X369199Y1919750D03*
X369999Y1901950D03*
X388499Y1959550D03*
Y1950550D03*
Y1932950D03*
X389499Y1913050D03*
Y1904050D03*
X349499Y1910050D03*
X348499Y1956550D03*
X347999Y1944550D03*
Y1925550D03*
X348999Y1898050D03*
X406999Y1905050D03*
X405999Y1951550D03*
X405499Y1939550D03*
Y1920550D03*
X406499Y1893050D03*
X385099Y1975950D03*
X420799Y1977250D03*
X399299Y1976750D03*
X367299Y1972950D03*
X420500Y1987000D03*
X403500D03*
X364999Y1987050D03*
X382499Y1987550D03*
X345499D03*
X463499Y29550D03*
X436499Y50350D03*
Y31350D03*
X466799Y64750D03*
X465799Y43750D03*
Y24750D03*
X499999Y64050D03*
X500499Y47050D03*
X499999Y25550D03*
X432999Y6050D03*
X448499D03*
X467999Y5550D03*
X485499Y6050D03*
X498999D03*
X437499Y71350D03*
X442799Y142450D03*
X441799Y121450D03*
Y102450D03*
X471399Y124550D03*
X470399Y103550D03*
Y84550D03*
X473099Y141050D03*
X499999Y145550D03*
X500499Y126050D03*
Y108550D03*
Y79550D03*
Y94050D03*
X502899Y217150D03*
X504199Y193250D03*
X472999Y214550D03*
X483599Y179350D03*
X446799Y205650D03*
X445799Y184650D03*
Y165650D03*
X474099Y181050D03*
X473099Y160050D03*
X449999Y217050D03*
X430499D03*
X499999Y164550D03*
X466399Y304950D03*
X479299Y297250D03*
X437499Y307050D03*
Y289550D03*
Y275050D03*
X444499Y283050D03*
X463999Y283550D03*
X481499D03*
X495999D03*
X448999Y255550D03*
X469999Y254550D03*
X508499Y255050D03*
X488999Y254550D03*
X438999Y381550D03*
X458499Y382050D03*
X484900Y394700D03*
X485000Y373200D03*
X509999Y382550D03*
X443499Y354050D03*
X464499Y353050D03*
X502999Y353550D03*
X483499Y353050D03*
X498399Y470050D03*
X503699Y419250D03*
X472499Y458050D03*
X468799Y414250D03*
X443199Y440850D03*
X440099Y459250D03*
X431099Y479350D03*
X450300Y404200D03*
X490499Y464050D03*
X490999Y444550D03*
Y427050D03*
Y412550D03*
X454499Y472550D03*
X454999Y438550D03*
X454499Y458050D03*
X453999Y417550D03*
X430099Y551450D03*
X485299Y534550D03*
X508699Y498950D03*
X471499Y493950D03*
X452499Y565050D03*
X456499Y518050D03*
X435499Y519050D03*
X491499Y504050D03*
X490499Y483050D03*
X453999Y509550D03*
X454499Y490050D03*
X504499Y598050D03*
Y580550D03*
Y566050D03*
X479999Y598550D03*
Y581050D03*
Y566550D03*
X509999Y640550D03*
X452499Y597050D03*
Y579550D03*
X427999Y597550D03*
Y580050D03*
Y565550D03*
X506599Y711650D03*
X487299Y716950D03*
X451099Y711650D03*
X450399Y672750D03*
X444799Y687350D03*
X509999Y672550D03*
Y655050D03*
X488499Y691050D03*
Y673550D03*
Y659050D03*
X463999Y691550D03*
Y674050D03*
Y659550D03*
X467699Y772750D03*
X468699Y788350D03*
X472999Y736550D03*
X489599Y752450D03*
X490299Y734550D03*
X453399Y807950D03*
X452099Y781450D03*
Y762450D03*
X435299Y795150D03*
Y777650D03*
Y763150D03*
X437299Y744650D03*
X495999Y795050D03*
X460999Y819550D03*
X475699Y880450D03*
X479599Y847550D03*
X462999Y884050D03*
Y865050D03*
X453399Y826950D03*
X434799Y833650D03*
Y814650D03*
X464499Y896050D03*
X493499Y884050D03*
Y865050D03*
X493999Y845550D03*
Y813550D03*
Y828050D03*
X506899Y919950D03*
Y900950D03*
X443599Y945650D03*
X442599Y924650D03*
Y905650D03*
X486799Y941050D03*
X485799Y920050D03*
Y901050D03*
X461999Y966050D03*
X462499Y946550D03*
Y914550D03*
Y929050D03*
X494099Y1017350D03*
X493099Y996350D03*
X462499Y1043850D03*
X461999Y985050D03*
X474499Y1115050D03*
X491999Y1115550D03*
X454999D03*
X439499D03*
X501499Y1102550D03*
X463999Y1102050D03*
X481499Y1102550D03*
X444499D03*
X428999D03*
X436999Y1142550D03*
Y1128050D03*
X504399Y1132250D03*
X473099Y1144550D03*
X453499Y1140550D03*
X484499Y1085850D03*
X483499Y1064850D03*
X433599Y1085550D03*
X432599Y1064550D03*
X463499Y1083850D03*
X462499Y1062850D03*
X437599Y1150050D03*
X487099Y1218050D03*
X486499Y1210550D03*
Y1196050D03*
X443199Y1224250D03*
X507199Y1224350D03*
X506599Y1202350D03*
Y1216850D03*
X505399Y1153250D03*
X474099Y1165550D03*
X454499Y1161550D03*
X443799Y1274250D03*
Y1246250D03*
Y1265250D03*
X443199Y1238750D03*
X507199Y1252350D03*
Y1243350D03*
X465499Y1284550D03*
Y1293550D03*
Y1265550D03*
X498299Y1323350D03*
X468999Y1323950D03*
X428499Y1325350D03*
X508599Y1370550D03*
X444899Y1377950D03*
X434499Y1360250D03*
X448099Y1341250D03*
X473999Y1342450D03*
X485599Y1367550D03*
X468699Y1362850D03*
X466699Y1378150D03*
X498899Y1386450D03*
X499199Y1350550D03*
X459699Y1468050D03*
X464199Y1401450D03*
X459999Y1424050D03*
X498899Y1408350D03*
X500899Y1434350D03*
X505899Y1466250D03*
X482599Y1449950D03*
X456399Y1445950D03*
X445099Y1464250D03*
X478299Y1464850D03*
X481499Y1417050D03*
Y1402550D03*
X441499Y1431550D03*
Y1414050D03*
Y1399550D03*
X499699Y1538950D03*
X466999Y1530650D03*
X488299Y1531050D03*
X461399Y1541650D03*
X474299Y1544750D03*
X452199Y1550650D03*
X444299Y1532650D03*
X439599Y1552150D03*
X465999Y1603450D03*
X487099Y1606250D03*
X449199Y1579050D03*
X443799Y1612250D03*
X460199Y1632850D03*
X484999Y1636550D03*
X501399Y1634550D03*
X508199Y1610450D03*
X510100Y1579800D03*
X472299Y1572050D03*
X502199Y1566250D03*
X472499Y1620550D03*
Y1611550D03*
X484200Y1579900D03*
X432499Y1617550D03*
X434500Y1579500D03*
X431999Y1605550D03*
X435300Y1715300D03*
X448399Y1699450D03*
X447699Y1682850D03*
X449599Y1656950D03*
X483599Y1662550D03*
X485599Y1694850D03*
X502899Y1709650D03*
X507399Y1683350D03*
X509199Y1660550D03*
X468499Y1712550D03*
X467999Y1687050D03*
Y1696050D03*
Y1668050D03*
X432400Y1680100D03*
X428600Y1691200D03*
X436799Y1772550D03*
X472699Y1792150D03*
X429499Y1748050D03*
X458499Y1742050D03*
X441499Y1758050D03*
X480999Y1756050D03*
X463999Y1772050D03*
X445499Y1792550D03*
X508200Y1758200D03*
X484999Y1779050D03*
X496999Y1799550D03*
X436499Y1836550D03*
X481299Y1811150D03*
X448099Y1809450D03*
X499999Y1854950D03*
X480499Y1855450D03*
X464999D03*
X443999Y1855950D03*
X476199Y1877450D03*
X434299Y1876050D03*
X446999Y1880050D03*
X492999Y1878050D03*
X504799Y1967550D03*
Y1939550D03*
Y1958550D03*
X505799Y1921050D03*
Y1912050D03*
Y1893050D03*
X475199Y1951950D03*
Y1923950D03*
Y1942950D03*
X476199Y1905450D03*
Y1896450D03*
X459299Y1966850D03*
Y1938850D03*
Y1957850D03*
X460299Y1920350D03*
Y1911350D03*
Y1892350D03*
X433299Y1950550D03*
Y1922550D03*
Y1941550D03*
X434299Y1904050D03*
Y1895050D03*
X445999Y1954550D03*
Y1945550D03*
Y1926550D03*
X446999Y1908050D03*
Y1899050D03*
X493499Y1909050D03*
X492499Y1955550D03*
X491999Y1943550D03*
Y1924550D03*
X492999Y1897050D03*
X509299Y1977250D03*
X493799D03*
X473299D03*
X455799Y1976750D03*
X436299Y1977250D03*
X492500Y1987500D03*
X476000Y1987000D03*
X456500Y1987500D03*
X438999Y1987550D03*
X522899Y64350D03*
Y45350D03*
X587999Y63550D03*
X588499Y46550D03*
X587999Y25050D03*
X541499Y63550D03*
X541999Y46550D03*
X541499Y25050D03*
X516499Y6550D03*
X535999D03*
X551499D03*
X570999Y6050D03*
X588499Y6550D03*
X523899Y85350D03*
X520299Y141450D03*
Y122450D03*
X569099Y112550D03*
X568099Y91550D03*
Y72550D03*
X562799Y146750D03*
Y127750D03*
X587999Y145050D03*
X588499Y125550D03*
X541499Y145050D03*
X541999Y125550D03*
Y108050D03*
Y79050D03*
Y93550D03*
X565999Y199950D03*
X528799D03*
X521299Y162450D03*
X563799Y167750D03*
X587999Y217050D03*
X568499Y217550D03*
X552999D03*
X533499D03*
X588999Y185050D03*
X587999Y164050D03*
X542499Y185050D03*
X541499Y164050D03*
X544799Y293950D03*
X540099Y306550D03*
X516899Y306950D03*
X515499Y284050D03*
X536499Y283050D03*
X525999Y255050D03*
X540499D03*
X572999Y287050D03*
X572499Y306550D03*
X572999Y269550D03*
Y255050D03*
X558099Y335050D03*
X557933Y331010D03*
X557999Y322550D03*
Y326550D03*
X579899Y375750D03*
X530999Y381550D03*
X520499Y353550D03*
X548100Y362200D03*
X573499Y346550D03*
X572499Y325550D03*
X577899Y460550D03*
X578399Y441050D03*
X577399Y420050D03*
X539799Y466050D03*
X538799Y445050D03*
X576099Y481850D03*
X511299Y449150D03*
X519499Y471550D03*
X518999Y416550D03*
X592499Y478050D03*
Y459050D03*
X592999Y439550D03*
Y422050D03*
Y407550D03*
X556499Y467550D03*
X555999Y412550D03*
X539299Y485550D03*
X576599Y522350D03*
X577099Y502850D03*
X579499Y561550D03*
X558499Y562550D03*
X538999Y562050D03*
X535499Y545050D03*
X514499Y546050D03*
X518999Y508550D03*
X519499Y489050D03*
X555999Y504550D03*
X556499Y485050D03*
X558499Y616050D03*
X554304Y615840D03*
X554499Y624550D03*
X558699D03*
X554499Y620050D03*
X558709Y620245D03*
X534499Y640050D03*
X586299Y711250D03*
X565699Y710650D03*
X549999Y710050D03*
X547999Y728550D03*
X573499Y690550D03*
Y673050D03*
Y658550D03*
X534499Y672050D03*
Y654550D03*
Y805950D03*
X511199Y782050D03*
X527499Y747150D03*
X525499Y772450D03*
X547499Y799050D03*
Y780050D03*
X547999Y760550D03*
Y743050D03*
X575499Y802050D03*
X575999Y782550D03*
Y765050D03*
X577999Y732050D03*
X575999Y750550D03*
X526499Y851150D03*
X510899Y868150D03*
X578299Y895650D03*
X541399Y873450D03*
Y854450D03*
X512899Y842550D03*
Y823550D03*
X521999Y895550D03*
X522499Y876050D03*
X576499Y842050D03*
X575499Y821050D03*
X583299Y961450D03*
X578299Y914650D03*
X540299Y956850D03*
X539299Y935850D03*
X570899Y965850D03*
Y946850D03*
X521999Y914550D03*
X562999Y898050D03*
X560499Y968050D03*
X560999Y948550D03*
Y916550D03*
Y931050D03*
X516499Y957050D03*
X514499Y975550D03*
X583299Y980450D03*
X534599Y1048550D03*
X571899Y986850D03*
X573499Y1055550D03*
Y1036550D03*
X541899Y1021450D03*
X540899Y1000450D03*
Y981450D03*
X560499Y987050D03*
X560999Y999050D03*
X558999Y1049550D03*
Y1017550D03*
Y1032050D03*
X513999Y1046050D03*
Y1027050D03*
X514499Y1007550D03*
Y990050D03*
X588499Y1101550D03*
X578999Y1114550D03*
X568499Y1101550D03*
X564499Y1116050D03*
X548999D03*
X529499D03*
X511999Y1115550D03*
X553999Y1103050D03*
X538499D03*
X518999D03*
X535599Y1069550D03*
X574499Y1076550D03*
X558499Y1088050D03*
Y1069050D03*
X547099Y1202750D03*
Y1221750D03*
X546499Y1180750D03*
Y1195250D03*
X567999Y1215550D03*
Y1206550D03*
Y1187550D03*
X527999Y1212550D03*
X527499Y1200550D03*
Y1181550D03*
X579299Y1300750D03*
X527499Y1278150D03*
X530499Y1297050D03*
X561099Y1301050D03*
X566399Y1273850D03*
X549399Y1302850D03*
Y1274850D03*
Y1293850D03*
X548799Y1252850D03*
Y1267350D03*
X547099Y1230750D03*
X583299Y1283250D03*
Y1255250D03*
Y1274250D03*
X582699Y1233250D03*
Y1247750D03*
X565999Y1248550D03*
Y1234050D03*
X525999Y1263050D03*
Y1245550D03*
Y1231050D03*
X555699Y1322950D03*
X581999Y1370150D03*
X559099Y1343250D03*
X545099Y1355250D03*
X518499Y1346950D03*
X540399Y1382150D03*
X523999Y1391050D03*
X523499Y1360050D03*
Y1379050D03*
X580999Y1412750D03*
X575699Y1438950D03*
X538799Y1409750D03*
X536799Y1436350D03*
X528499Y1460250D03*
X546099Y1467550D03*
X582999Y1461250D03*
X557499Y1443050D03*
Y1452050D03*
Y1424050D03*
X516999Y1437050D03*
X517499Y1449050D03*
X516999Y1418050D03*
X563499Y1497550D03*
Y1486550D03*
Y1503550D03*
Y1492050D03*
X590599Y1483450D03*
X529799Y1555050D03*
X567999Y1549950D03*
X582299Y1534150D03*
X538999Y1528350D03*
X518899Y1530150D03*
X532499Y1635550D03*
X552099Y1601950D03*
X553399Y1624550D03*
X590799Y1627850D03*
X588000Y1604000D03*
X588099Y1572050D03*
X552199Y1576650D03*
X569499Y1619550D03*
Y1610550D03*
X573400Y1577600D03*
X529499Y1616550D03*
X533800Y1575500D03*
X528999Y1604550D03*
X518499Y1643950D03*
X538299Y1721050D03*
X532599Y1655650D03*
X554199Y1651950D03*
X555199Y1674750D03*
X555399Y1689350D03*
X555899Y1706750D03*
X580299Y1722550D03*
X590599Y1694450D03*
X580799Y1646150D03*
X572999Y1694550D03*
Y1703550D03*
Y1675550D03*
X532499Y1688550D03*
X532999Y1700550D03*
X532499Y1669550D03*
X582599Y1740050D03*
X560399Y1792550D03*
X555500Y1802700D03*
X539499Y1788150D03*
X526499Y1801150D03*
X556199Y1727050D03*
X522300Y1739200D03*
X532499Y1763050D03*
X515499Y1779050D03*
X544300Y1784638D03*
X587499Y1844550D03*
X531799Y1818450D03*
X514199Y1815750D03*
X591499Y1855950D03*
X573999Y1855450D03*
X554499Y1855950D03*
X538999D03*
X517499Y1855450D03*
X588899Y1882350D03*
X562599Y1874450D03*
X519399Y1876750D03*
X533499Y1884050D03*
X575999Y1888050D03*
X587899Y1956850D03*
Y1928850D03*
Y1947850D03*
X588899Y1910350D03*
Y1901350D03*
X561599Y1948950D03*
Y1920950D03*
Y1939950D03*
X562599Y1902450D03*
Y1893450D03*
X546999Y1966850D03*
Y1938850D03*
Y1957850D03*
X547999Y1920350D03*
Y1911350D03*
Y1892350D03*
X518399Y1951250D03*
Y1923250D03*
Y1942250D03*
X519399Y1904750D03*
Y1895750D03*
X532499Y1958550D03*
Y1949550D03*
Y1930550D03*
X533499Y1912050D03*
Y1903050D03*
X575999Y1907050D03*
X576499Y1919050D03*
X574999Y1953550D03*
X575499Y1965550D03*
X574999Y1934550D03*
X585799Y1976250D03*
X570299D03*
X546299Y1977250D03*
X528799Y1976750D03*
X568999Y1987050D03*
X553499D03*
X588499Y1986550D03*
X511999Y1987550D03*
X531500Y1987500D03*
X603999Y54350D03*
Y35350D03*
X651799Y59650D03*
Y40650D03*
X674999Y59050D03*
X675499Y42050D03*
X674999Y20550D03*
X624499Y61550D03*
X624999Y44550D03*
X624499Y23050D03*
X608499Y6550D03*
X625999Y7050D03*
X645499D03*
X660999D03*
X604999Y75350D03*
X603999Y133750D03*
X652799Y80650D03*
X649899Y138350D03*
X674999Y140550D03*
X675499Y121050D03*
Y103550D03*
Y74550D03*
Y89050D03*
X624499Y143050D03*
X624999Y123550D03*
X623899Y202550D03*
X604999Y173750D03*
X603999Y152750D03*
X650899Y178350D03*
X649899Y157350D03*
X662499Y218050D03*
X642999D03*
X625499Y217550D03*
X605499D03*
X675999Y180550D03*
X674999Y159550D03*
X625499Y183050D03*
X624499Y162050D03*
X656499Y307050D03*
X653999Y286550D03*
X627999Y280050D03*
X627499Y299550D03*
X627999Y262550D03*
Y248050D03*
X614999Y371550D03*
X599799Y385150D03*
X600299Y365650D03*
X599299Y344650D03*
X659899Y363250D03*
X632399Y358750D03*
X635399Y376250D03*
X607399Y380250D03*
X643599Y395950D03*
X655999Y344050D03*
X656499Y324550D03*
X628499Y339550D03*
X628200Y320000D03*
X644099Y450950D03*
X644599Y416950D03*
X644099Y436450D03*
X621499Y466550D03*
X621999Y432550D03*
X621499Y452050D03*
X620999Y411550D03*
X666999Y476550D03*
X643499Y546750D03*
X642499Y525750D03*
X613700Y504600D03*
X621499Y484050D03*
X593499Y499050D03*
X666499Y547050D03*
X666999Y508550D03*
X666499Y528050D03*
X666999Y491050D03*
X642999Y566250D03*
X640599Y604650D03*
X673999Y645150D03*
X645099Y639150D03*
X631999Y639650D03*
X665999Y623550D03*
X620499D03*
Y609050D03*
X595999Y641550D03*
Y624050D03*
Y609550D03*
X674999Y601550D03*
X646999Y584550D03*
X625999Y585050D03*
X606499Y584550D03*
X667499Y568050D03*
X651999Y718350D03*
X648999Y702350D03*
X629099Y714050D03*
X605299Y661750D03*
X609499Y708050D03*
X607499Y726550D03*
X647499Y689050D03*
Y671550D03*
Y657050D03*
X622999Y689550D03*
Y672050D03*
X597999Y690050D03*
X647399Y742150D03*
X653099Y803350D03*
X621499Y767150D03*
X633499Y750150D03*
X606999Y797050D03*
Y778050D03*
X607499Y758550D03*
Y741050D03*
X664999Y805050D03*
Y786050D03*
X665499Y766550D03*
X645799Y816650D03*
X642599Y883250D03*
X641599Y862250D03*
Y843250D03*
X621999Y835050D03*
X612999Y854550D03*
X629499Y853050D03*
Y868550D03*
X613499Y868050D03*
X663499Y896050D03*
X663999Y876550D03*
Y844550D03*
Y859050D03*
X665999Y826050D03*
X636999Y914050D03*
X639499Y971150D03*
Y952150D03*
X616699Y967250D03*
Y948250D03*
X658999Y959050D03*
X656999Y977550D03*
X603499Y904050D03*
X601499Y954550D03*
Y922550D03*
Y937050D03*
X664499Y936050D03*
X663499Y915050D03*
X673999Y1036550D03*
Y1017550D03*
X674699Y1061450D03*
X611399Y1045650D03*
Y1026650D03*
X617699Y988250D03*
X656499Y1048050D03*
Y1029050D03*
X656999Y1009550D03*
Y992050D03*
X631999Y1001550D03*
X629999Y1052050D03*
Y1020050D03*
Y1034550D03*
X600999Y1002050D03*
X598999Y1052550D03*
Y1020550D03*
Y1035050D03*
X633999Y1103050D03*
X669499Y1116550D03*
X616499Y1115050D03*
X605999Y1102050D03*
X598999Y1114550D03*
X674699Y1080450D03*
X674999Y1134950D03*
X641799Y1137650D03*
X627699Y1143550D03*
X612399Y1066650D03*
X629499Y1090550D03*
Y1071550D03*
X598499Y1091050D03*
Y1072050D03*
X603899Y1157850D03*
X626199Y1183450D03*
X597599Y1196050D03*
X596599Y1215050D03*
X651599Y1203050D03*
X650599Y1182050D03*
X651299Y1174150D03*
X650299Y1153150D03*
X668199Y1173850D03*
X667199Y1152850D03*
X671199Y1213750D03*
X670199Y1192750D03*
X628699Y1164550D03*
X668699Y1227650D03*
X672999Y1303450D03*
X608899Y1305050D03*
X600899Y1238650D03*
X630499Y1243950D03*
X657099Y1272850D03*
X657799Y1288450D03*
X656399Y1307050D03*
X618199Y1296250D03*
Y1268250D03*
Y1287250D03*
X617599Y1246250D03*
Y1260750D03*
X638999Y1286550D03*
Y1295550D03*
Y1267550D03*
X598499Y1280550D03*
X598999Y1292550D03*
X598499Y1261550D03*
X671999Y1324950D03*
X631799Y1322650D03*
X605599Y1326350D03*
X665699Y1337250D03*
X606199Y1338250D03*
X617899Y1360850D03*
X625499Y1383450D03*
X632499Y1347950D03*
X599999Y1382550D03*
X599499Y1351550D03*
Y1370550D03*
X654999Y1385050D03*
X654499Y1373050D03*
Y1354050D03*
X659699Y1445950D03*
X604899Y1407750D03*
X601299Y1447650D03*
X636799Y1461250D03*
X626799Y1432350D03*
X627499Y1406050D03*
X665699Y1462250D03*
X652999Y1435550D03*
Y1418050D03*
Y1403550D03*
X656099Y1479550D03*
X625199Y1489150D03*
X610899Y1496750D03*
X672399Y1508750D03*
X673699Y1535350D03*
X662099Y1549650D03*
X643099Y1541350D03*
X599799Y1544650D03*
X617699Y1530350D03*
X670699Y1603150D03*
X671399Y1625350D03*
X628499Y1636650D03*
X633499Y1615450D03*
X635500Y1603900D03*
X652399Y1575850D03*
X623499Y1564050D03*
X652499Y1618550D03*
Y1609550D03*
X639200Y1576200D03*
X612499Y1615550D03*
X611900Y1577900D03*
X611999Y1603550D03*
X649399Y1644950D03*
X657099Y1668850D03*
X635099Y1691150D03*
X607599Y1716450D03*
X593399Y1668850D03*
X627299Y1659550D03*
X600599Y1645450D03*
X674999Y1676550D03*
X656499Y1697050D03*
X609499Y1692050D03*
Y1675050D03*
X642499Y1709050D03*
X665399Y1752350D03*
X650399Y1771250D03*
X593299Y1760950D03*
X619499Y1803150D03*
X627273Y1793905D03*
X606999Y1745550D03*
X625499Y1725050D03*
X675499Y1757050D03*
X675999Y1769050D03*
X675499Y1738050D03*
X642400Y1800100D03*
X659159Y1792278D03*
X626999Y1800050D03*
X645099Y1877550D03*
X667999Y1870950D03*
X632799Y1820450D03*
X627494Y1829068D03*
X608599Y1810750D03*
X669399Y1855350D03*
X627499Y1855950D03*
X611999D03*
X630699Y1872750D03*
X602799Y1887350D03*
X640999Y1815550D03*
X595199Y1820910D03*
X659549Y1815384D03*
X644049Y1810834D03*
X633837Y1807384D03*
X646799Y1926450D03*
X645399Y1906150D03*
X673899Y1966850D03*
Y1938850D03*
Y1957850D03*
X674899Y1920350D03*
Y1911350D03*
Y1892350D03*
X660299Y1964550D03*
Y1936550D03*
Y1955550D03*
X661299Y1918050D03*
Y1909050D03*
Y1890050D03*
X629699Y1947250D03*
Y1919250D03*
Y1938250D03*
X630699Y1900750D03*
Y1891750D03*
X601799Y1961850D03*
Y1933850D03*
Y1952850D03*
X602799Y1915350D03*
Y1906350D03*
X616499Y1913050D03*
Y1922050D03*
Y1894050D03*
X615499Y1959550D03*
Y1968550D03*
Y1940550D03*
X644999Y1953050D03*
X645499Y1965050D03*
X644999Y1934050D03*
X659299Y1976250D03*
X643799D03*
X622799D03*
X605299Y1975750D03*
X642499Y1987050D03*
X626999D03*
X661999Y1986550D03*
X605999Y1987050D03*
X751499Y48350D03*
X694999Y62650D03*
X757499Y63050D03*
Y44050D03*
X725499Y62050D03*
X725999Y45050D03*
X725499Y23550D03*
X680499Y6550D03*
X697999Y7050D03*
X712499Y6050D03*
X729999Y6550D03*
X749499D03*
X752099Y112150D03*
X738199Y137450D03*
X695999Y102650D03*
X694999Y81650D03*
X699699Y141750D03*
X758499Y84050D03*
X725499Y143550D03*
X725999Y124050D03*
Y106550D03*
Y77550D03*
Y92050D03*
X757999Y154550D03*
Y159050D03*
X753999Y154550D03*
Y159050D03*
X728899Y204550D03*
X688999Y196550D03*
X700699Y181750D03*
X699699Y160750D03*
X749499Y218550D03*
X729499D03*
X711999Y218050D03*
X677999D03*
X726499Y183550D03*
X725499Y162550D03*
X755499Y314550D03*
X751539Y313984D03*
X711999Y307550D03*
Y293050D03*
X723200Y275500D03*
X711499Y252550D03*
X680500Y280700D03*
X682999Y300050D03*
X683499Y263050D03*
Y248550D03*
X755346Y319149D03*
X751499Y318050D03*
X748000Y357500D03*
X703999Y385550D03*
X749899Y398550D03*
X711499Y344550D03*
X711999Y325050D03*
X683999Y340050D03*
X682999Y319050D03*
X713699Y455450D03*
X713199Y474950D03*
X712699Y434450D03*
X750399Y453550D03*
X750899Y419550D03*
X750399Y439050D03*
X694999Y480550D03*
X737999Y467050D03*
X691399Y548350D03*
X755699Y528650D03*
X756199Y509150D03*
X755199Y488150D03*
X754499Y564650D03*
X713099Y561550D03*
X713599Y542050D03*
X712599Y521050D03*
X713199Y489450D03*
X695499Y521050D03*
X695999Y501550D03*
X737999Y559050D03*
X738499Y539550D03*
Y522050D03*
Y507550D03*
X738999Y488050D03*
X691899Y588850D03*
X692399Y569350D03*
X754999Y605150D03*
X755499Y585650D03*
X717099Y636050D03*
X729699Y640350D03*
X731499Y604050D03*
Y586550D03*
Y572050D03*
X690499Y623050D03*
X744999Y626550D03*
X721499Y617550D03*
X699999Y610050D03*
X751499Y679148D03*
X749499Y716050D03*
X744999Y715550D03*
X749999Y720050D03*
X745499D03*
X757400Y686300D03*
X720899Y712250D03*
X732499Y729250D03*
X681899Y713650D03*
X679299Y703050D03*
X727099Y715050D03*
X739399Y688150D03*
X747999Y670750D03*
X723499Y654850D03*
X693999Y648150D03*
X754999Y694050D03*
X702999Y688050D03*
Y670550D03*
Y656050D03*
X678499Y688550D03*
Y671050D03*
X749999Y700050D03*
X750000Y755500D03*
X710899Y751150D03*
X696299Y741850D03*
X685999Y780050D03*
X694599Y763450D03*
X743099Y785350D03*
X733799Y761450D03*
X716599Y736850D03*
X723999Y802350D03*
Y783350D03*
X687099Y804650D03*
X706999Y811550D03*
Y792550D03*
X707499Y773050D03*
X728499Y841850D03*
X724999Y823350D03*
X688099Y844650D03*
X687099Y823650D03*
X729999Y881850D03*
Y862850D03*
X751599Y887350D03*
X705999Y851050D03*
Y865550D03*
X707999Y832550D03*
X751499Y855550D03*
Y836550D03*
X751999Y817050D03*
X707399Y918550D03*
Y899550D03*
X678299Y978350D03*
X730999Y902850D03*
X688099Y936350D03*
X687099Y915350D03*
Y896350D03*
X724699Y976250D03*
X723699Y955250D03*
Y936250D03*
X752599Y927350D03*
X751599Y906350D03*
X706499Y942550D03*
X749999Y965550D03*
Y946550D03*
X751399Y1023550D03*
Y1004550D03*
X752399Y1052550D03*
X734999Y1030550D03*
Y1045050D03*
X713999Y1049050D03*
Y1031550D03*
Y1017050D03*
X678299Y997350D03*
X694999Y993050D03*
X692999Y1043550D03*
Y1011550D03*
Y1026050D03*
X750999Y986550D03*
X755499Y1119050D03*
X749999Y1119550D03*
X748999Y1115550D03*
X748499Y1111550D03*
X734999Y1062550D03*
X713499Y1068550D03*
X737999Y1119050D03*
X727499Y1106050D03*
X720499Y1118550D03*
X709999Y1105550D03*
X700499Y1118550D03*
X689999Y1105550D03*
X727499Y1132650D03*
X704299D03*
X692499Y1082050D03*
Y1063050D03*
X753999Y1100050D03*
X747000Y1159000D03*
X713599Y1214650D03*
X756799Y1217650D03*
X758799Y1190150D03*
Y1199150D03*
X717999Y1169150D03*
X716999Y1148150D03*
X714399Y1199750D03*
X713399Y1178750D03*
X735999Y1220550D03*
Y1206050D03*
X737999Y1187550D03*
Y1178550D03*
Y1159550D03*
X695999Y1217550D03*
Y1203050D03*
X697999Y1184550D03*
X697499Y1172550D03*
Y1153550D03*
X684299Y1249550D03*
X740799Y1298750D03*
X723499Y1292650D03*
Y1278150D03*
X725499Y1250650D03*
Y1259650D03*
Y1231650D03*
X755399Y1300650D03*
Y1286150D03*
X757399Y1258650D03*
Y1267650D03*
Y1239650D03*
X756799Y1232150D03*
X709699Y1264550D03*
X708699Y1243550D03*
X740499Y1252550D03*
Y1270050D03*
X695999Y1235050D03*
X739199Y1348950D03*
X742099Y1320650D03*
X719199Y1322350D03*
X695999Y1323350D03*
X677999Y1347550D03*
X680299Y1365850D03*
X713899Y1386450D03*
X707899Y1346250D03*
X734199Y1373850D03*
X694999Y1388050D03*
Y1379050D03*
Y1360050D03*
X702299Y1404450D03*
X736199Y1399050D03*
X741099Y1450250D03*
X737799Y1428350D03*
X716899Y1459850D03*
X700899Y1450250D03*
X681299Y1393150D03*
X678299Y1425050D03*
X686999Y1468850D03*
X719499Y1446650D03*
X721899Y1419050D03*
X754999Y1420050D03*
Y1437550D03*
X692999Y1421050D03*
Y1406550D03*
X751000Y1517000D03*
X757500Y1522500D03*
X751000Y1521000D03*
Y1525000D03*
X741099Y1498150D03*
X729199Y1492750D03*
X716199Y1503050D03*
X735799Y1533650D03*
X714599Y1533950D03*
X708899Y1549250D03*
X685299Y1551950D03*
X747199Y1509150D03*
X755499Y1507550D03*
X734499Y1563550D03*
X722199Y1564250D03*
X706700Y1579900D03*
X698599Y1568550D03*
X681299Y1579150D03*
X693599Y1602450D03*
X686699Y1638650D03*
X742000Y1560000D03*
X743400Y1578700D03*
X719999Y1605050D03*
X751300Y1604900D03*
X732999Y1620050D03*
X756299Y1679050D03*
X738799Y1677250D03*
X750099Y1694950D03*
X756499Y1712150D03*
X739199Y1716750D03*
X721199Y1723750D03*
X727399Y1694350D03*
X717099Y1702450D03*
X693099Y1722350D03*
X691999Y1660550D03*
X751999Y1775550D03*
X756617Y1780067D03*
X752657Y1779496D03*
X755999Y1775550D03*
X756900Y1766000D03*
X753558Y1769946D03*
X757518Y1770517D03*
X752900Y1766000D03*
X751899Y1752150D03*
X747799Y1766750D03*
X729499Y1778750D03*
X729999Y1756450D03*
X747499Y1734350D03*
X702599Y1730550D03*
X709099Y1751850D03*
X690499Y1744950D03*
X694599Y1768450D03*
X715999Y1763050D03*
Y1772050D03*
Y1744050D03*
X693549Y1793134D03*
X706549Y1793634D03*
X744049Y1791634D03*
X740549Y1802634D03*
X753949Y1798194D03*
X717000Y1812384D03*
X705000Y1811900D03*
X686999Y1870250D03*
X728099Y1844750D03*
X747599Y1844250D03*
X743799Y1888850D03*
X728299D03*
X753699Y1879250D03*
X732199Y1878750D03*
X744699Y1868450D03*
X758399Y1868350D03*
X723199Y1867950D03*
X743399Y1855850D03*
X725899Y1855350D03*
X690899Y1855850D03*
X706399D03*
X697999Y1844550D03*
X732999Y1868550D03*
X711500Y1817700D03*
X704300Y1828400D03*
X686473Y1818375D03*
X740549Y1810384D03*
X755999Y1935050D03*
X750000Y1965500D03*
X696299Y1898850D03*
X716599Y1918450D03*
X728799Y1933050D03*
X709199Y1962950D03*
X698299Y1948050D03*
X676399Y1901150D03*
X695299Y1926450D03*
X711899Y1944050D03*
X736799Y1919450D03*
X728799Y1908150D03*
X705599Y1891850D03*
X730499Y1954650D03*
X755299Y1902150D03*
X739799D03*
X685499Y1959050D03*
Y1968050D03*
Y1940050D03*
X755500Y1914500D03*
X756499Y1942550D03*
X721499Y1974550D03*
X696299Y1976250D03*
X678799Y1975750D03*
X754999Y1987550D03*
X737499Y1987050D03*
X717999Y1987550D03*
X702499D03*
X679499Y1987050D03*
X759999Y39550D03*
X774399Y54050D03*
X763399Y24150D03*
X817599Y43750D03*
X824899Y25150D03*
X813299Y68350D03*
Y49350D03*
X796999Y65550D03*
X797499Y48550D03*
X796999Y27050D03*
X764999Y6550D03*
X784499Y6050D03*
X801999Y6550D03*
X818999Y6050D03*
X836499Y6550D03*
X840499Y55050D03*
X839999Y46050D03*
X840999Y62550D03*
X778399Y105250D03*
X775399Y80250D03*
X821199Y137450D03*
X813299Y110850D03*
X805899Y126150D03*
X767399Y140150D03*
X796599Y123450D03*
X814299Y89350D03*
X796999Y147050D03*
X797499Y127550D03*
Y110050D03*
Y81050D03*
Y95550D03*
X837499Y138550D03*
X838499Y145050D03*
X837999Y91050D03*
X838999Y85050D03*
X838499Y99550D03*
Y107050D03*
X839499Y119050D03*
X841499Y71550D03*
X760799Y181950D03*
X779399Y200550D03*
X786499Y219050D03*
X800999Y216550D03*
X766999Y219050D03*
X797999Y187050D03*
X796999Y166050D03*
X838999Y313550D03*
X821499Y314050D03*
X809373Y307571D03*
Y297571D03*
Y292571D03*
X808999Y303050D03*
X796873Y307571D03*
Y303071D03*
Y298571D03*
Y294071D03*
X822200Y258000D03*
X816500Y270600D03*
X795199Y333050D03*
X789999Y340250D03*
X776199Y323050D03*
X784478Y355424D03*
Y359924D03*
X781478Y363924D03*
X776978D03*
X772478Y359924D03*
Y363924D03*
X839299Y390950D03*
X819299Y394250D03*
X838499Y352050D03*
X772873Y330624D03*
X840299Y430950D03*
X839299Y409950D03*
X820299Y434250D03*
X819299Y413250D03*
X802999Y466050D03*
X774999Y476550D03*
Y462050D03*
X825399Y540950D03*
X825899Y521450D03*
X824899Y500450D03*
X835599Y564050D03*
X834599Y543050D03*
X802999Y558050D03*
X803499Y538550D03*
Y521050D03*
Y506550D03*
X803999Y487050D03*
X775499Y553550D03*
X774499Y532550D03*
X774999Y494050D03*
X774499Y513550D03*
X835099Y583550D03*
X814499Y601550D03*
Y584050D03*
Y569550D03*
X789999Y602050D03*
Y584550D03*
Y570050D03*
X785499Y641050D03*
X777499Y638050D03*
X791999Y729350D03*
X770999Y726750D03*
X771800Y686600D03*
X786500Y686100D03*
X798000Y686400D03*
X764599Y655750D03*
X777499Y664550D03*
X794999D03*
X806300Y670600D03*
X841000Y671100D03*
X766499Y699050D03*
X782999Y699550D03*
X836149Y714050D03*
X766499Y705550D03*
X806831Y701853D03*
Y706853D03*
Y711853D03*
X794331Y698353D03*
Y702853D03*
Y707353D03*
Y711853D03*
X806999Y697050D03*
X820900Y668000D03*
X812800Y679900D03*
X785826Y737954D03*
X771196Y764382D03*
Y760382D03*
X775696Y764382D03*
X780196D03*
X783196Y760382D03*
Y755882D03*
X799385Y757436D03*
Y761436D03*
X778999Y806950D03*
X763099Y796350D03*
X835999Y799050D03*
Y781550D03*
Y767050D03*
X811499Y799550D03*
Y782050D03*
Y767550D03*
X837799Y754150D03*
X774199Y733050D03*
X825199Y850850D03*
X827699Y892450D03*
Y873450D03*
X776199Y879250D03*
X775199Y858250D03*
Y839250D03*
X800999Y892550D03*
X802999Y874050D03*
X801999Y853050D03*
Y834050D03*
X802499Y814550D03*
X828699Y913450D03*
X826999Y963150D03*
X773199Y960650D03*
X772199Y939650D03*
Y920650D03*
X800499Y944050D03*
Y963050D03*
X800999Y924550D03*
Y907050D03*
Y1037550D03*
Y1005550D03*
Y1020050D03*
X827999Y1003150D03*
X826999Y982150D03*
X777899Y1028050D03*
X776899Y1007050D03*
Y988050D03*
X801499Y984050D03*
X795854Y1135926D03*
X768306Y1124321D03*
X783999Y1096550D03*
X760999Y1095550D03*
X789499Y1099550D03*
X773499Y1101050D03*
X769499D03*
X773499Y1105050D03*
X769499D03*
X836149Y1118550D03*
X774383Y1133235D03*
X788854Y1142626D03*
X782672Y1129146D03*
X811499Y1097050D03*
X807499D03*
X807341Y1116216D03*
Y1111216D03*
Y1101216D03*
X806999Y1106050D03*
X802499Y1097566D03*
X798499D03*
X825500Y1076300D03*
X815400Y1082500D03*
X806899Y1151850D03*
X783333Y1157392D03*
Y1161892D03*
X780333Y1165892D03*
X775833D03*
X771333Y1161892D03*
Y1165892D03*
X808299Y1175850D03*
X806599Y1189750D03*
X803599Y1211050D03*
X831499Y1209550D03*
Y1200550D03*
Y1181550D03*
X789499Y1225050D03*
X791499Y1206550D03*
X790999Y1194550D03*
Y1175550D03*
X839999Y1157550D03*
X811999Y1293550D03*
X826199Y1294450D03*
X828199Y1267850D03*
X788999Y1278150D03*
X791999Y1294450D03*
X808199Y1290350D03*
Y1275850D03*
X810199Y1248350D03*
Y1257350D03*
Y1229350D03*
X829499Y1242550D03*
Y1228050D03*
X789499Y1257050D03*
Y1239550D03*
X825500Y1379000D03*
X831499Y1324950D03*
X795299Y1326650D03*
X822199Y1335250D03*
X819199Y1353550D03*
X798299Y1344250D03*
X779399Y1361850D03*
X762499Y1335550D03*
Y1353050D03*
X799999Y1340550D03*
Y1358050D03*
X806499Y1390550D03*
X803299Y1426650D03*
X773999Y1393450D03*
X763399Y1401450D03*
X781999Y1434650D03*
X805899Y1464250D03*
X771399Y1474550D03*
X806499Y1408050D03*
X834499Y1397550D03*
X836600Y1416500D03*
X774542Y1526350D03*
X804899Y1553250D03*
X769300Y1488100D03*
X779000Y1488400D03*
X786500Y1488600D03*
X801300Y1489000D03*
X770999Y1500050D03*
X780499D03*
X839499Y1523550D03*
X773499Y1509050D03*
X769499D03*
X786999Y1506550D03*
X774488Y1537495D03*
X787799Y1543550D03*
X797699Y1541050D03*
X809245Y1518722D03*
Y1508722D03*
Y1503722D03*
X795999Y1518550D03*
Y1514050D03*
Y1509550D03*
Y1504550D03*
X808999Y1513550D03*
X785827Y1561296D03*
Y1565796D03*
X782827Y1569796D03*
X778327D03*
X773327Y1565796D03*
X773827Y1569796D03*
X813300Y1604100D03*
X827199Y1622750D03*
X841499Y1638950D03*
X803599Y1618350D03*
X826499Y1609050D03*
X825999Y1578050D03*
X839899Y1562050D03*
X829200Y1719800D03*
X824100Y1719900D03*
X819400Y1721900D03*
X837199Y1660550D03*
X814599Y1642650D03*
X776999Y1647650D03*
X797299Y1646650D03*
X802899Y1670550D03*
X839199Y1683550D03*
X808899Y1698450D03*
X779999Y1717050D03*
X770399Y1699650D03*
X765099Y1664950D03*
X823499Y1693050D03*
Y1702050D03*
Y1674050D03*
X782999Y1687050D03*
X783499Y1699050D03*
X782999Y1668050D03*
X819200Y1727100D03*
X808299Y1755250D03*
X794499Y1734550D03*
X770099Y1730350D03*
X779899Y1748150D03*
X787900Y1758800D03*
X765600Y1756800D03*
X827999Y1791550D03*
X767159Y1792364D03*
X829799Y1856350D03*
X809299D03*
X791799Y1855850D03*
X801099Y1844750D03*
X785599D03*
X765099D03*
X780799Y1888850D03*
X763299Y1888350D03*
X833100Y1878500D03*
X806199Y1879250D03*
X788699Y1878750D03*
X769199Y1879250D03*
X833199Y1868450D03*
X818900Y1870800D03*
X797199Y1868450D03*
X779699Y1867950D03*
X779399Y1855850D03*
X763899D03*
X833999Y1883050D03*
X773999Y1923550D03*
X767999Y1923050D03*
X774499Y1930050D03*
X768999D03*
X783814Y1967213D03*
Y1971713D03*
X783499Y1907050D03*
X774499Y1908050D03*
X765999D03*
X838999Y1928550D03*
X790499Y1913050D03*
X775999Y1916050D03*
X840999Y1970550D03*
X768499Y1917550D03*
X775199Y1940050D03*
X799297Y1959333D03*
X835114Y1951150D03*
X790844Y1952360D03*
X795526Y1909696D03*
X795493Y1913696D03*
X795501Y1917696D03*
X795499Y1922050D03*
X807997Y1922865D03*
X808005Y1918865D03*
X807936Y1914865D03*
Y1910365D03*
X784016Y1975708D03*
X775814Y1975699D03*
X771814Y1975713D03*
X813599Y1979950D03*
X789299Y1983850D03*
X829499Y1980250D03*
X829999Y1987550D03*
X812499Y1987050D03*
X792999Y1987550D03*
X777499D03*
X902999Y22050D03*
X917499Y21550D03*
X909499D03*
X902499Y35050D03*
X909999Y35550D03*
X916499Y36050D03*
X844799Y19850D03*
X860799Y24150D03*
X885999Y21150D03*
X855999Y6550D03*
X871499D03*
X890999Y6050D03*
X908499Y6550D03*
X923999Y6050D03*
X849999Y44550D03*
X854499Y39550D03*
X865499D03*
X883999Y39050D03*
X893999Y46550D03*
X848499Y67550D03*
X904999Y61550D03*
Y67550D03*
X905499Y56550D03*
X890700Y132500D03*
X872100Y132700D03*
X854300Y132600D03*
X891999Y146050D03*
X919542Y124007D03*
X849499Y91050D03*
X843499Y82550D03*
X855499Y82050D03*
X878499Y91550D03*
X876999Y82050D03*
X867499D03*
X845999Y111050D03*
X886499Y99550D03*
Y104550D03*
X890459Y100116D03*
X890499Y104550D03*
X847999Y119550D03*
X881999D03*
X865499Y125550D03*
X875499D03*
X918499Y107050D03*
X898999Y104550D03*
X904499Y121550D03*
X856499Y71050D03*
X881499Y70550D03*
X866999D03*
X890999Y73050D03*
X904499Y74050D03*
X906999Y224150D03*
X887400Y233555D03*
X871786Y233924D03*
Y218924D03*
Y203924D03*
X907999Y264150D03*
X906999Y243150D03*
X906399Y314250D03*
Y295250D03*
X863999Y313550D03*
X887400Y259700D03*
X879878Y247724D03*
X872999Y294624D03*
X869399Y288124D03*
X864199Y321524D03*
X907399Y335250D03*
X875799Y386250D03*
X904999Y385050D03*
Y370550D03*
X854499Y387550D03*
Y373050D03*
X858400Y352300D03*
X847999Y352550D03*
X870600Y346700D03*
X872599Y336224D03*
X876799Y426250D03*
X875799Y405250D03*
X884399Y462450D03*
Y443450D03*
X905499Y462050D03*
X904499Y441050D03*
Y422050D03*
X904999Y402550D03*
X854999Y464550D03*
X853999Y443550D03*
X854499Y405050D03*
X853999Y424550D03*
X861199Y546050D03*
X860199Y525050D03*
X885399Y483450D03*
X914699Y524650D03*
X913699Y503650D03*
Y484650D03*
X860699Y565550D03*
X898999Y622050D03*
Y604550D03*
X860499Y607550D03*
X861800Y591200D03*
X918999Y641550D03*
X870719Y609705D03*
X894000Y642400D03*
X870719Y639705D03*
X870773Y624705D03*
X903999Y574378D03*
X870499Y724550D03*
X866499D03*
X895999Y720050D03*
Y702550D03*
X900999Y670050D03*
Y652550D03*
X918499Y712050D03*
X918999Y673550D03*
X918499Y693050D03*
X918999Y656050D03*
X887401Y665000D03*
X881200Y652100D03*
X859999Y713050D03*
X871385Y719436D03*
X871786Y709482D03*
X871499Y689436D03*
X871786Y679436D03*
X860796Y678632D03*
X921399Y796350D03*
X921899Y776850D03*
Y759350D03*
Y744850D03*
X884499Y799050D03*
Y781550D03*
Y767050D03*
X859999Y799550D03*
Y782050D03*
Y767550D03*
X919499Y733050D03*
X856299Y753150D03*
X846799Y754150D03*
X865000Y752100D03*
X889699Y876050D03*
X847799Y828250D03*
X857099Y873450D03*
X920399Y886850D03*
Y869350D03*
Y854850D03*
X922399Y836350D03*
X921399Y815350D03*
X898499Y862050D03*
Y844550D03*
Y830050D03*
X873999Y862550D03*
Y845050D03*
Y830550D03*
X886999Y947250D03*
Y907350D03*
X867199Y941350D03*
X866199Y920350D03*
Y901350D03*
X850999Y962550D03*
Y943550D03*
X919899Y925350D03*
X920899Y946350D03*
X919899Y906350D03*
X851999Y983550D03*
X921499Y1031050D03*
X920999Y1050550D03*
X921499Y1013550D03*
Y999050D03*
X870468Y1030227D03*
X880033Y1058592D03*
X886919Y1044478D03*
X870298Y1045227D03*
X870777Y1014948D03*
X868750Y1128750D03*
X921999Y1090550D03*
X920999Y1069550D03*
X887400Y1070600D03*
X859999Y1118550D03*
X841999D03*
X860499Y1192550D03*
X845799Y1190450D03*
X849799Y1199750D03*
X846499Y1170450D03*
X897299Y1182450D03*
X887999Y1209350D03*
X871399Y1201850D03*
Y1210850D03*
Y1182850D03*
X892499Y1224550D03*
X851999Y1218550D03*
X856400Y1157700D03*
X848999Y1158050D03*
X863300Y1153800D03*
X872099Y1268150D03*
X871399Y1291450D03*
X860099Y1295450D03*
X869399Y1243850D03*
Y1229350D03*
X890499Y1285550D03*
Y1271050D03*
X892499Y1252550D03*
Y1243550D03*
X850499Y1300050D03*
Y1282550D03*
Y1268050D03*
X852499Y1249550D03*
X851999Y1237550D03*
X875399Y1322650D03*
X868499Y1392550D03*
X890999Y1336550D03*
Y1354050D03*
X841999Y1341050D03*
Y1358550D03*
X861849Y1383500D03*
X873499Y1356050D03*
X870294Y1375659D03*
X894499Y1423550D03*
Y1441050D03*
X868499Y1410050D03*
X886913Y1449010D03*
X879727Y1463696D03*
X871836Y1450460D03*
Y1435460D03*
Y1420460D03*
X863838Y1542478D03*
X864799Y1532050D03*
X914599Y1521650D03*
X910899Y1549250D03*
X894499Y1522050D03*
Y1539550D03*
X895499Y1488050D03*
X902759Y1509585D03*
X861999Y1522550D03*
X843999Y1523550D03*
X887499Y1476050D03*
X865300Y1557700D03*
X866516Y1498533D03*
X923599Y1634350D03*
X909700Y1576400D03*
X907500Y1604000D03*
X908899Y1630050D03*
X868099Y1635650D03*
X887299Y1620050D03*
X886900Y1604100D03*
X873099Y1572550D03*
X850099Y1572250D03*
X849900Y1605100D03*
X852499Y1621350D03*
X866499Y1603050D03*
Y1612050D03*
X864000Y1578200D03*
X858400Y1561900D03*
X850499Y1562050D03*
X879200Y1698700D03*
X879900Y1709300D03*
X883900Y1709500D03*
X855350Y1703201D03*
X914899Y1657550D03*
X922599Y1682150D03*
X903599Y1686850D03*
X895999Y1661250D03*
X877699Y1646650D03*
X855799Y1658250D03*
X882999Y1678250D03*
X864099Y1683550D03*
X842799Y1701150D03*
X875900Y1709500D03*
X902900Y1709800D03*
X886506Y1721300D03*
X860085Y1715214D03*
X892517Y1714217D03*
X882200Y1744800D03*
X886400Y1744400D03*
X842500Y1799000D03*
X892700Y1727800D03*
X879399Y1798150D03*
X911299Y1800850D03*
X864000Y1748000D03*
X866699Y1770950D03*
X853799Y1790850D03*
X844499Y1788050D03*
X892700Y1736500D03*
X904814Y1789113D03*
X870783Y1742817D03*
X863099Y1813150D03*
X903299Y1814750D03*
X894999Y1829050D03*
X922899Y1853650D03*
X905299Y1852650D03*
X900299Y1876950D03*
X842199Y1879250D03*
X914999Y1887050D03*
Y1868050D03*
X862499Y1823550D03*
X854977Y1818994D03*
X887401Y1881500D03*
X894000Y1868452D03*
X887499Y1855550D03*
X869999Y1855972D03*
X871836Y1840972D03*
X869634Y1826876D03*
X864414Y1944050D03*
Y1940050D03*
X914899Y1912450D03*
X916599Y1942650D03*
X897599Y1938750D03*
X914899Y1972250D03*
X873399Y1963650D03*
X904299Y1954950D03*
X897299Y1904150D03*
X907599Y1930050D03*
X915499Y1899050D03*
X861414Y1928550D03*
X843999D03*
X856999Y1970050D03*
X849999Y1970550D03*
X865200Y1968000D03*
X863699Y1902750D03*
X861000Y1917500D03*
X879399Y1974550D03*
X850499Y1977950D03*
X868699Y1983250D03*
X921499Y1986550D03*
X901999Y1987050D03*
X864999D03*
X849499D03*
X884499Y1986550D03*
X974699Y64650D03*
X977399Y44050D03*
X954799Y17850D03*
X974699Y21450D03*
X991399Y22450D03*
X1002699Y40050D03*
X991999Y56050D03*
X941499Y6550D03*
X960999D03*
X976499D03*
X995999Y6050D03*
X967499Y47050D03*
Y56050D03*
Y64050D03*
X945499Y33550D03*
X940499Y33050D03*
X929999Y32550D03*
X927999Y38050D03*
X928499Y51550D03*
X943499Y48050D03*
Y55050D03*
X951899Y45550D03*
X934999Y67050D03*
X928999Y56050D03*
X928499Y60550D03*
X928999Y65550D03*
X942999Y61550D03*
Y66550D03*
X983099Y83650D03*
X1005299Y71350D03*
X977699Y109150D03*
X994399Y101250D03*
X981099Y123450D03*
X939199Y142050D03*
X968399Y137150D03*
X967999Y73050D03*
Y82050D03*
X945499Y116550D03*
X961568Y113567D03*
X943499Y72550D03*
Y78050D03*
X951499Y81050D03*
X988699Y174350D03*
X967399Y180350D03*
X956099Y181350D03*
X958799Y167350D03*
X1004799Y231450D03*
X1005299Y211950D03*
Y194450D03*
Y179950D03*
X952799Y231150D03*
Y213650D03*
Y199150D03*
X982999Y203550D03*
Y221050D03*
Y189050D03*
X932499Y223550D03*
Y206050D03*
Y191550D03*
X1005299Y305450D03*
Y290950D03*
X1005799Y271450D03*
X1004799Y250450D03*
X952799Y310150D03*
X953299Y290650D03*
X952299Y269650D03*
Y250650D03*
X983999Y316050D03*
Y301550D03*
X933499Y304050D03*
X983499Y280550D03*
X982499Y259550D03*
Y240550D03*
X932999Y283050D03*
X931999Y262050D03*
Y243050D03*
X1005799Y382450D03*
X1004799Y361450D03*
X1005299Y322950D03*
X1004799Y342450D03*
X952299Y380650D03*
X952799Y342150D03*
X952299Y361650D03*
X952799Y324650D03*
X984499Y393050D03*
X983499Y372050D03*
Y353050D03*
X983999Y333550D03*
X933999Y395550D03*
X932999Y374550D03*
X933499Y336050D03*
X932999Y355550D03*
X933499Y318550D03*
X966199Y473350D03*
X1000699Y482350D03*
Y463350D03*
X954799Y451650D03*
Y434150D03*
Y419650D03*
X953299Y401650D03*
X983499Y464050D03*
X983999Y427050D03*
Y444550D03*
Y412550D03*
X933499Y447050D03*
X932999Y466550D03*
X933499Y429550D03*
Y415050D03*
X967199Y513350D03*
X966199Y492350D03*
X1001699Y503350D03*
X1003499Y546350D03*
X1003999Y526850D03*
X951299Y560150D03*
Y541150D03*
X951799Y521650D03*
Y504150D03*
Y489650D03*
X985999Y536550D03*
Y554050D03*
Y522050D03*
X935499Y556550D03*
Y539050D03*
Y524550D03*
X984499Y504050D03*
X983499Y483050D03*
X933999Y506550D03*
X932999Y485550D03*
X967799Y606350D03*
X966799Y585350D03*
Y566350D03*
X1005999Y636350D03*
Y618850D03*
X1004499Y586350D03*
X1005999Y604350D03*
X1003499Y565350D03*
X950299Y631650D03*
Y614150D03*
Y599650D03*
X952299Y581150D03*
X969499Y639050D03*
X986499Y613550D03*
X985499Y592550D03*
Y573550D03*
X935999Y616050D03*
X934999Y595050D03*
Y576050D03*
X949799Y670150D03*
X950799Y691150D03*
X949799Y651150D03*
X969999Y730550D03*
X968999Y709550D03*
Y690550D03*
X969499Y653550D03*
Y671050D03*
Y795750D03*
X969999Y776250D03*
Y758750D03*
Y744250D03*
X994499Y803550D03*
Y784550D03*
X994999Y747550D03*
Y765050D03*
Y733050D03*
X943999Y806050D03*
X944499Y767550D03*
X943999Y787050D03*
X944499Y750050D03*
Y735550D03*
X970499Y879750D03*
Y862250D03*
Y847750D03*
Y835750D03*
X969499Y814750D03*
X992999Y894550D03*
X993499Y857550D03*
Y875050D03*
Y843050D03*
X942999Y877550D03*
Y860050D03*
Y845550D03*
X995499Y824550D03*
X944999Y827050D03*
X994499Y973550D03*
Y956050D03*
Y941550D03*
X949299Y977450D03*
X970999Y939250D03*
X969999Y918250D03*
Y899250D03*
X993999Y934550D03*
X992999Y913550D03*
X943499Y937050D03*
X942499Y916050D03*
Y897050D03*
X994999Y1033050D03*
Y1045050D03*
X993999Y1012050D03*
Y993050D03*
X948799Y1047950D03*
Y1028950D03*
X949299Y1009450D03*
Y991950D03*
X971499Y1048050D03*
X971999Y1011050D03*
Y1028550D03*
Y996550D03*
X949799Y1068950D03*
Y1080950D03*
X998599Y1128450D03*
Y1110950D03*
Y1096450D03*
X950699Y1139750D03*
Y1122250D03*
Y1107750D03*
X975999Y1115550D03*
Y1133050D03*
Y1101050D03*
X925499Y1135550D03*
Y1118050D03*
Y1103550D03*
X972499Y1088050D03*
X971499Y1067050D03*
X999099Y1214450D03*
Y1199950D03*
Y1187950D03*
X998099Y1147950D03*
Y1166950D03*
X951199Y1225750D03*
Y1211250D03*
Y1199250D03*
X950199Y1159250D03*
Y1178250D03*
X976499Y1219050D03*
Y1204550D03*
X925999Y1221550D03*
Y1207050D03*
X976499Y1192550D03*
X975499Y1171550D03*
Y1152550D03*
X925999Y1195050D03*
X924999Y1174050D03*
Y1155050D03*
X999599Y1291450D03*
X998599Y1270450D03*
Y1251450D03*
X999099Y1231950D03*
X951699Y1302750D03*
X950699Y1281750D03*
Y1262750D03*
X951199Y1243250D03*
X976999Y1296050D03*
X975999Y1275050D03*
Y1256050D03*
X976499Y1236550D03*
X926499Y1298550D03*
X925499Y1277550D03*
X925999Y1239050D03*
X925499Y1258550D03*
X975100Y1342600D03*
X1000700Y1358100D03*
X996500Y1324800D03*
X952499Y1361850D03*
X944000Y1391900D03*
X943799Y1380850D03*
Y1342950D03*
X965099Y1324350D03*
X928499Y1325350D03*
X976499Y1377050D03*
Y1362550D03*
X925999Y1379550D03*
Y1365050D03*
X973500Y1474000D03*
X971500Y1467500D03*
X971700Y1457800D03*
Y1462300D03*
X972000Y1442000D03*
Y1437500D03*
X971700Y1448300D03*
Y1452800D03*
X962500Y1436500D03*
Y1441000D03*
X952800Y1437500D03*
Y1442000D03*
X962000Y1466500D03*
X966000Y1475000D03*
X952300Y1467500D03*
X958800Y1472500D03*
X962200Y1447300D03*
Y1451800D03*
X952500Y1448300D03*
Y1452800D03*
X962200Y1456800D03*
Y1461300D03*
X952500Y1457800D03*
Y1462300D03*
X992500Y1397300D03*
X964400Y1409700D03*
X946700Y1426500D03*
X994200Y1421500D03*
X924999Y1471050D03*
X926499Y1456550D03*
X925499Y1435550D03*
X925999Y1397050D03*
X925499Y1416550D03*
X972549Y1502300D03*
Y1506800D03*
X973500Y1483000D03*
Y1478500D03*
X973200Y1488300D03*
X972700Y1497300D03*
X966000Y1479500D03*
Y1484000D03*
X958800Y1477000D03*
Y1481500D03*
X965700Y1489300D03*
X960200Y1495300D03*
X958500Y1486800D03*
X951500Y1495300D03*
X960049Y1500300D03*
X951349D03*
X960049Y1504800D03*
X951349D03*
X973200Y1516400D03*
X972500Y1529100D03*
X966600D03*
X961400Y1528700D03*
X961900Y1522400D03*
X967100Y1522800D03*
X973000D03*
X962100Y1516000D03*
X967300Y1516400D03*
X972700Y1534800D03*
X972000Y1547500D03*
X966100D03*
X960900Y1547100D03*
X961400Y1540800D03*
X966600Y1541200D03*
X972500D03*
X961600Y1534400D03*
X966800Y1534800D03*
X972700Y1553300D03*
X961600Y1552900D03*
X966800Y1553300D03*
X944000Y1511300D03*
X943199Y1531650D03*
X924499Y1541550D03*
X924999Y1503050D03*
X924499Y1522550D03*
X924999Y1485550D03*
X972000Y1566000D03*
X966100D03*
X960900Y1565600D03*
X961400Y1559300D03*
X966600Y1559700D03*
X972500D03*
X973000Y1572800D03*
X972300Y1585500D03*
X966400D03*
X961200Y1585100D03*
X961700Y1578800D03*
X966900Y1579200D03*
X972800D03*
X961900Y1572400D03*
X967100Y1572800D03*
X972400Y1592000D03*
X966500D03*
X961300Y1591600D03*
X972200Y1598400D03*
X966300D03*
X961100Y1598000D03*
X960600Y1604300D03*
X971700Y1604700D03*
X965800D03*
X944499Y1632650D03*
X925599Y1612050D03*
X933199Y1577550D03*
X925499Y1562550D03*
X950100Y1626100D03*
X989999Y1718050D03*
X958799Y1715750D03*
X957799Y1646950D03*
X955499Y1690850D03*
X941499Y1679550D03*
X940499Y1656950D03*
X931499Y1702050D03*
X941800Y1787700D03*
X934200Y1793500D03*
X993299Y1734350D03*
X994999Y1748950D03*
X976600Y1757100D03*
X965349Y1742000D03*
X949799Y1756250D03*
X976399Y1772250D03*
X954499Y1783550D03*
X941499Y1776250D03*
X932199Y1801850D03*
X971000Y1803000D03*
X999999Y1775250D03*
X976399Y1791150D03*
X993499Y1805550D03*
X928000Y1818500D03*
X1003599Y1846650D03*
X995699Y1858950D03*
X971500Y1871500D03*
X937199Y1869950D03*
X993499Y1824550D03*
Y1833550D03*
X987999Y1971950D03*
Y1949050D03*
X1000999Y1946350D03*
X991999Y1915750D03*
X966799Y1892150D03*
X974699Y1914450D03*
X945199Y1946350D03*
X955799Y1951950D03*
X954099Y1915450D03*
X938199Y1917150D03*
X1002500Y1953500D03*
X1001599Y1921450D03*
X992299Y1929050D03*
X989999Y1962650D03*
X980999Y1933350D03*
X947499Y1936050D03*
X946199Y1966650D03*
X937499Y1893850D03*
X971499Y1956050D03*
Y1965050D03*
Y1937050D03*
X930999Y1950050D03*
X931499Y1962050D03*
X930999Y1931050D03*
X955499Y1893050D03*
Y1902050D03*
X953799Y1977950D03*
X930199Y1979550D03*
X1005000Y1980500D03*
X994999Y1986550D03*
X973999D03*
X956499Y1986050D03*
X936999Y1986550D03*
X1022000Y15500D03*
X1013499Y6550D03*
X1020499Y50550D03*
X1020999Y33050D03*
X1010599Y115550D03*
X1020499Y122550D03*
X1020999Y105050D03*
Y85550D03*
Y70050D03*
X1021499Y141050D03*
X1020999Y230550D03*
X1021499Y213050D03*
Y193550D03*
Y178050D03*
X1020999Y158550D03*
Y304550D03*
Y289050D03*
X1020499Y269550D03*
X1020999Y252050D03*
X1020499Y341550D03*
X1020999Y324050D03*
X1020499Y391550D03*
X1020999Y374050D03*
X1007299Y432450D03*
Y414950D03*
Y400450D03*
X1020499Y463550D03*
X1020999Y446050D03*
Y426550D03*
Y411050D03*
X1021999Y558550D03*
Y539050D03*
Y523550D03*
X1021499Y504050D03*
X1021999Y486550D03*
X1021499Y576050D03*
X1020999Y642550D03*
X1020499Y623050D03*
X1020999Y605550D03*
X1020499Y695050D03*
X1020999Y677550D03*
Y658050D03*
Y720050D03*
X1020499Y809550D03*
X1020999Y792050D03*
Y772550D03*
Y757050D03*
X1020499Y737550D03*
Y880550D03*
Y865050D03*
X1019999Y845550D03*
X1020499Y828050D03*
X1019999Y917550D03*
X1020499Y900050D03*
X1019999Y971050D03*
X1019499Y951550D03*
X1019999Y934050D03*
Y986550D03*
Y1058550D03*
Y1043050D03*
X1019499Y1023550D03*
X1019999Y1006050D03*
X1020499Y1134050D03*
Y1118550D03*
X1019999Y1099050D03*
X1020499Y1081550D03*
X1019499Y1198550D03*
Y1183050D03*
X1018999Y1163550D03*
X1019499Y1146050D03*
X1016999Y1219050D03*
X1016499Y1301050D03*
Y1236550D03*
X1016999Y1256050D03*
Y1271550D03*
X1023300Y1344400D03*
X1024300Y1365200D03*
X1022599Y1322950D03*
X1024300Y1393600D03*
X1008599Y1716050D03*
X1022299Y1715750D03*
X1008999Y1702450D03*
X1016899Y1731650D03*
X1026899Y1768550D03*
X1020299Y1746650D03*
X1015299Y1765950D03*
X1009999Y1797450D03*
X1022499Y1802050D03*
X1022999Y1784550D03*
X1011299Y1860650D03*
X1007599Y1818450D03*
X1022999Y1821550D03*
Y1837050D03*
X1020499Y1877550D03*
X1020999Y1860050D03*
Y1912550D03*
Y1897050D03*
X1017499Y1954550D03*
X1017999Y1937050D03*
Y1987050D03*
X1023000Y1973000D03*
G54D22*
G01X987100Y1624900D02*
X988302Y1626102D01*
X1004307D01*
G01X981200Y1625800D02*
X986198Y1630798D01*
X991710D01*
X992014Y1631102D01*
X1004307D01*
G54D13*
X12560Y211435D03*
Y207498D03*
Y203561D03*
Y199624D03*
Y195687D03*
Y191750D03*
Y187813D03*
Y183876D03*
Y179939D03*
Y176002D03*
Y172065D03*
Y231121D03*
Y227184D03*
Y223247D03*
Y246869D03*
Y242932D03*
Y238995D03*
Y235058D03*
X12569Y395663D03*
Y391726D03*
Y387789D03*
Y383852D03*
Y379915D03*
Y375978D03*
Y372041D03*
Y478342D03*
Y474405D03*
Y470468D03*
Y466531D03*
Y462594D03*
Y458657D03*
Y454720D03*
Y450783D03*
Y446846D03*
Y442909D03*
Y438972D03*
Y435035D03*
Y431098D03*
Y427161D03*
Y423223D03*
Y411411D03*
Y407474D03*
Y403537D03*
Y399600D03*
Y561019D03*
Y557082D03*
Y553145D03*
Y549208D03*
Y545271D03*
Y541334D03*
Y537397D03*
Y533460D03*
Y529523D03*
Y525586D03*
Y521649D03*
Y517712D03*
Y513775D03*
Y509838D03*
Y505901D03*
Y501964D03*
Y498027D03*
Y494090D03*
Y490153D03*
Y486216D03*
Y482279D03*
Y643696D03*
Y639759D03*
Y635822D03*
Y631885D03*
Y627948D03*
Y624011D03*
Y620074D03*
Y616137D03*
Y612200D03*
Y604326D03*
Y608263D03*
Y600389D03*
Y596452D03*
Y592515D03*
Y584641D03*
Y588578D03*
Y580704D03*
Y576767D03*
Y572830D03*
Y568893D03*
Y564956D03*
Y698814D03*
Y694877D03*
Y690940D03*
Y687003D03*
Y683066D03*
Y679129D03*
Y675192D03*
Y671255D03*
Y667318D03*
Y663381D03*
Y659444D03*
Y655507D03*
Y651570D03*
Y647633D03*
X12560Y813010D03*
Y809073D03*
Y805136D03*
Y801199D03*
Y797262D03*
Y793325D03*
Y789388D03*
Y785451D03*
Y781514D03*
Y820884D03*
Y816947D03*
Y856318D03*
Y852381D03*
Y848444D03*
Y844507D03*
Y840570D03*
Y836633D03*
Y832696D03*
Y1195687D03*
Y1191750D03*
Y1187813D03*
Y1183876D03*
Y1179939D03*
Y1176002D03*
Y1172065D03*
Y1168128D03*
Y1164191D03*
Y1160254D03*
Y1156317D03*
Y1223247D03*
Y1219310D03*
Y1215373D03*
Y1211436D03*
Y1207499D03*
Y1231121D03*
Y1227184D03*
X12569Y1391726D03*
Y1387789D03*
Y1383852D03*
Y1379915D03*
Y1375978D03*
Y1372041D03*
Y1368104D03*
Y1364167D03*
Y1360230D03*
Y1356293D03*
Y1474405D03*
Y1470468D03*
Y1466531D03*
Y1462594D03*
Y1458657D03*
Y1454720D03*
Y1450783D03*
Y1446846D03*
Y1442909D03*
Y1438972D03*
Y1435035D03*
Y1431098D03*
Y1427161D03*
Y1423224D03*
Y1419287D03*
Y1415350D03*
Y1411413D03*
Y1407475D03*
Y1395663D03*
Y1557082D03*
Y1553145D03*
Y1549208D03*
Y1545271D03*
Y1541334D03*
Y1537397D03*
Y1533460D03*
Y1529523D03*
Y1525586D03*
Y1521649D03*
Y1517712D03*
Y1513775D03*
Y1509838D03*
Y1505901D03*
Y1501964D03*
Y1498027D03*
Y1494090D03*
Y1490153D03*
Y1486216D03*
Y1482279D03*
Y1478342D03*
Y1639759D03*
Y1635822D03*
Y1631885D03*
Y1627948D03*
Y1624011D03*
Y1620074D03*
Y1616137D03*
Y1612200D03*
Y1608263D03*
Y1604326D03*
Y1600389D03*
Y1596452D03*
Y1588578D03*
Y1592515D03*
Y1584641D03*
Y1580704D03*
Y1576767D03*
Y1568893D03*
Y1572830D03*
Y1564956D03*
Y1561019D03*
Y1683066D03*
Y1679129D03*
Y1675192D03*
Y1671255D03*
Y1667318D03*
Y1663381D03*
Y1659444D03*
Y1655507D03*
Y1651570D03*
Y1647633D03*
Y1643696D03*
X12560Y1805136D03*
Y1801199D03*
Y1797262D03*
Y1793325D03*
Y1789388D03*
Y1785451D03*
Y1781514D03*
Y1777577D03*
Y1773640D03*
Y1769703D03*
Y1765766D03*
Y1840570D03*
Y1836633D03*
Y1832696D03*
Y1828759D03*
Y1824822D03*
Y1820885D03*
Y1816948D03*
G54D23*
G01X97999Y199050D02*
X122999D01*
X140999Y181050D01*
X155999D01*
G01X194700Y1385700D02*
X194151D01*
X192999Y1386852D01*
Y1435550D01*
X223029Y1465580D01*
G01D02*
X229025Y1471576D01*
G01D02*
X260999Y1503550D01*
G01X226999Y1941050D02*
X223662Y1937713D01*
Y1929621D01*
X223436Y1929395D01*
Y1890465D01*
G54D14*
X8750Y1086250D03*
X8499Y1937550D03*
X5303Y1947050D03*
X11703Y1951946D03*
X93999Y58550D03*
X92900Y66128D03*
X89800Y132400D03*
X92999Y86128D03*
Y96128D03*
X74499Y84050D03*
Y80650D03*
X86899Y130567D03*
X86599Y126750D03*
X74999Y74050D03*
Y70550D03*
X78700Y70700D03*
Y74200D03*
X15750Y102250D03*
X41999Y200050D03*
X65999Y216050D03*
X95350Y204550D03*
X89800Y208550D03*
X24300Y247300D03*
X29699Y388484D03*
X29599Y382884D03*
X29999Y398684D03*
X23499Y397579D03*
X23399Y373931D03*
Y389679D03*
X23499Y381831D03*
X26299Y383854D03*
Y387629D03*
X28100Y374000D03*
X26492Y439350D03*
X26599Y442749D03*
X26299Y399601D03*
Y403376D03*
Y478404D03*
X26899Y454850D03*
X26515Y481798D03*
X45800Y405200D03*
X26799Y458497D03*
X26486Y462648D03*
X26499Y466250D03*
X64403Y471046D03*
X64397Y474446D03*
X26524Y426720D03*
X26399Y423322D03*
X29899Y404384D03*
X28900Y429200D03*
X29365Y421169D03*
X29500Y460800D03*
X28700Y451900D03*
X28800Y436700D03*
X28700Y445700D03*
X68000Y475600D03*
X67800Y469900D03*
X23499Y468447D03*
X23399Y476295D03*
Y444799D03*
X23499Y452699D03*
X23399Y460547D03*
Y429051D03*
X23499Y436951D03*
X23600Y405700D03*
X77499Y469550D03*
X61400Y452600D03*
X35900Y412600D03*
X65000Y455500D03*
X28900Y417800D03*
X39217Y554750D03*
X42867Y548450D03*
X43099Y555850D03*
X33699Y561850D03*
X46299Y552950D03*
X36499Y517775D03*
Y521550D03*
X26399Y501966D03*
Y505741D03*
X64600Y486300D03*
X64700Y489700D03*
X33307Y557938D03*
X26199Y547176D03*
X93200Y510500D03*
X83700Y529500D03*
X28600Y508500D03*
X35300Y524800D03*
X38400Y514900D03*
X88999Y538050D03*
X68900Y490600D03*
X68700Y485200D03*
X28600Y499300D03*
X26900Y532800D03*
X63499Y538550D03*
Y533050D03*
X22800Y539600D03*
X23499Y515691D03*
X23399Y523539D03*
X23499Y531439D03*
X23399Y492043D03*
X23499Y499943D03*
X23399Y507791D03*
X23499Y484195D03*
X77999Y493050D03*
X77499Y502550D03*
X29999Y557150D03*
X26599Y525648D03*
X95500Y513400D03*
X26599Y529302D03*
X60003Y534150D03*
X86199Y536025D03*
X59999Y537550D03*
X86199Y532250D03*
X65599Y514250D03*
X49799Y559150D03*
X68000Y546500D03*
X72500Y545000D03*
X27199Y539600D03*
X42202Y608195D03*
X39600Y626984D03*
X41400Y611500D03*
X42709Y625607D03*
X38300Y633800D03*
X41500Y642800D03*
X27499Y620203D03*
Y623857D03*
X36499Y566350D03*
X37999Y611550D03*
X42599Y567850D03*
X32800Y578200D03*
X47543Y578340D03*
X44959Y575756D03*
X30712Y624971D03*
X29999Y640550D03*
X60076Y595777D03*
X55499Y595650D03*
X29819Y634951D03*
X26869Y616861D03*
X23399Y641649D03*
X23499Y618053D03*
X23799Y625950D03*
X23499Y633801D03*
X23999Y609250D03*
X22978Y588571D03*
X22699Y577950D03*
X22999Y565550D03*
X57800Y634300D03*
X34976Y619250D03*
X44900Y642800D03*
X26568Y635950D03*
Y639604D03*
X47101Y632355D03*
X28000Y578500D03*
X25581Y567763D03*
X47626Y611300D03*
X45701Y607700D03*
X27699Y573750D03*
X82499Y627050D03*
X26800Y611500D03*
X41500Y635000D03*
X52500D03*
X48999Y642900D03*
X81251Y607249D03*
Y619251D03*
X28808Y593150D03*
X28700Y596549D03*
X32200Y603710D03*
X31598Y607102D03*
X80499Y664550D03*
X30999Y656250D03*
X29999Y694550D03*
X30999Y650550D03*
X81999Y668050D03*
X74499Y662050D03*
X25999Y694870D03*
X23999Y689050D03*
X23499Y665297D03*
X23699Y673150D03*
X23499Y681045D03*
Y649549D03*
X23725Y657471D03*
X78499Y654050D03*
X26737Y651957D03*
X26999Y656550D03*
X27687Y667447D03*
Y671101D03*
X76999Y664550D03*
X27700Y682700D03*
X50410Y695801D03*
X50300Y699200D03*
X44046Y799554D03*
X32800Y803050D03*
X46887Y803413D03*
X37416Y799033D03*
X37099Y811350D03*
X51100Y806300D03*
X49900Y813200D03*
X56281Y801350D03*
X27299Y783550D03*
X35300Y789375D03*
X90700Y792900D03*
X35559Y795112D03*
X45100Y793100D03*
X37216Y807951D03*
X76540Y850938D03*
X29299Y836901D03*
X75500Y847700D03*
X49300Y836500D03*
X46700Y820100D03*
X40400Y840792D03*
X89000Y816500D03*
X48346Y844529D03*
X58699Y837250D03*
X26299Y815050D03*
X92999Y868550D03*
X92499Y876550D03*
X68860Y838706D03*
X90000Y826000D03*
X54074Y815750D03*
X69499Y842950D03*
X62405Y820300D03*
X63499Y843050D03*
X90500Y831500D03*
X31699Y814350D03*
X65500Y817700D03*
X23299Y863050D03*
X26662Y861550D03*
X39649Y822000D03*
X80500Y817000D03*
X74220Y854150D03*
X72362Y849550D03*
X25000Y858100D03*
X46576Y832951D03*
X29600Y854000D03*
X24000Y853500D03*
X89400Y935400D03*
X89499Y942850D03*
X94999Y901550D03*
X85999Y940429D03*
X86399Y937050D03*
X29000Y896500D03*
X72000Y1013400D03*
X63273Y1023974D03*
X90000Y993100D03*
X92600Y996100D03*
X80699Y1004450D03*
Y1000450D03*
X20400Y1048300D03*
X66499Y1025050D03*
X75900Y1019100D03*
X63500Y1029600D03*
X88000Y1008500D03*
X75500Y1012261D03*
X80000Y1090500D03*
X80500Y1097550D03*
Y1104500D03*
X76999Y1196550D03*
X21817Y1156317D03*
X78499Y1273550D03*
X78613Y1282664D03*
X78779Y1302664D03*
X91279Y1340642D03*
X89999Y1348050D03*
X27499Y1387550D03*
X24499Y1389663D03*
X22851Y1374169D03*
X22999Y1366050D03*
X23700Y1354600D03*
X23499Y1381500D03*
X78779Y1312664D03*
X86165Y1339050D03*
X25507Y1372045D03*
X25558Y1368447D03*
X86890Y1346635D03*
Y1342860D03*
X28499Y1391050D03*
X32333Y1389383D03*
X20999Y1352050D03*
Y1320550D03*
X77758Y1357742D03*
X25000D03*
X30378Y1462518D03*
X33915Y1462681D03*
X32094Y1448448D03*
X28697Y1448296D03*
X33000Y1393000D03*
X33400Y1408100D03*
X36198Y1446749D03*
X26800Y1443800D03*
X30600Y1415100D03*
X30999Y1438050D03*
X27999Y1430050D03*
X29100Y1459200D03*
X34200Y1466200D03*
X23028Y1468579D03*
X23499Y1460550D03*
X22999Y1453050D03*
X23499Y1445050D03*
X22999Y1437050D03*
X23999Y1429050D03*
X23499Y1421550D03*
X23999Y1413550D03*
X32451Y1411468D03*
X28999Y1411550D03*
X33206Y1432352D03*
X30499Y1434550D03*
X30500Y1395500D03*
X76000Y1431100D03*
X34896Y1555730D03*
X34099Y1497550D03*
X30499D03*
X80043Y1544691D03*
X83932Y1544705D03*
X29631Y1533063D03*
X31999Y1517846D03*
Y1521500D03*
X46700Y1546793D03*
X34465Y1481683D03*
X30999Y1482050D03*
X44299Y1550950D03*
X96200Y1550100D03*
X32700Y1485200D03*
X28999Y1478050D03*
X27100Y1494300D03*
X34900Y1501000D03*
X35400Y1522200D03*
X35999Y1514550D03*
X29600Y1515300D03*
X24423Y1527123D03*
X22999Y1500050D03*
Y1515550D03*
X23799Y1508050D03*
X24499Y1492050D03*
X23599Y1476350D03*
X23277Y1484050D03*
X25247Y1546912D03*
X37999Y1530900D03*
X38500Y1534600D03*
X32099Y1535550D03*
X30115Y1511900D03*
X33512Y1512051D03*
X90324Y1538800D03*
X26705Y1534795D03*
X30199Y1545450D03*
X24199Y1523700D03*
X79000Y1555500D03*
X82429D03*
X36340Y1558809D03*
X78600Y1561900D03*
X29499Y1630050D03*
X75000Y1561800D03*
X28899Y1613524D03*
X42199Y1601050D03*
X38208Y1569841D03*
X25521Y1563350D03*
X30520Y1572049D03*
X32299Y1613524D03*
X34599Y1595300D03*
X24900Y1569500D03*
X31149Y1568300D03*
X26999Y1610550D03*
X34884Y1615734D03*
X32199Y1633124D03*
X34816Y1630953D03*
X22999Y1626050D03*
X23499Y1634050D03*
Y1618050D03*
X22699Y1594224D03*
X23499Y1610050D03*
Y1602050D03*
X23608Y1572653D03*
X24323Y1559950D03*
X31099Y1595350D03*
X32663Y1628181D03*
X27123Y1572205D03*
X33599Y1600200D03*
X74800Y1584700D03*
X74700Y1574600D03*
X39000Y1573500D03*
X89373Y1561073D03*
X85600Y1561500D03*
X80400Y1571766D03*
X82329Y1568117D03*
X31999Y1661127D03*
X28600Y1661039D03*
X29626Y1645002D03*
X33026Y1645051D03*
X95499Y1665418D03*
X33100Y1648500D03*
X47400Y1721700D03*
X34699Y1663300D03*
X27499Y1657050D03*
X26785Y1642089D03*
X22999Y1665550D03*
X92873Y1708176D03*
X24244Y1681868D03*
X22864Y1673550D03*
X23499Y1657050D03*
X23999Y1649550D03*
X23415Y1641634D03*
X92479Y1718176D03*
X78100Y1688189D03*
X92900Y1678176D03*
X93999Y1703050D03*
X74500Y1692000D03*
X21600Y1702900D03*
X32700Y1673300D03*
X32494Y1669706D03*
X29100Y1669500D03*
X30274Y1787238D03*
X85599Y1797350D03*
X38878Y1799571D03*
X47899Y1798650D03*
X36300Y1805123D03*
X35675Y1783450D03*
X39324Y1780623D03*
X39000Y1750800D03*
X43751Y1780559D03*
X42275Y1754000D03*
X48049Y1791450D03*
X40400Y1735600D03*
X47900Y1731300D03*
X47800Y1740500D03*
X89306Y1746856D03*
X89499Y1753575D03*
X85341Y1752245D03*
X85194Y1748848D03*
X46999Y1779550D03*
X37699Y1789850D03*
X46199Y1783050D03*
X74400Y1778100D03*
X38094Y1785840D03*
X41200Y1747050D03*
X42199Y1792250D03*
X37574Y1794050D03*
X45799Y1757650D03*
X46799Y1794900D03*
X47440Y1761391D03*
X31811Y1790271D03*
X47400Y1765250D03*
X43559Y1767884D03*
X40478Y1795820D03*
X32099Y1797150D03*
X47604Y1769005D03*
X45782Y1771877D03*
X47499Y1775350D03*
X45877Y1728477D03*
Y1724823D03*
X47000Y1737100D03*
X43600D03*
X28550Y1828153D03*
X29599Y1844350D03*
X29899Y1821050D03*
X34099Y1822850D03*
X60449Y1842550D03*
X80099Y1817250D03*
X28123Y1831527D03*
X35876Y1812350D03*
X34129Y1815267D03*
X86649Y1817100D03*
X61009Y1822340D03*
X36532Y1825352D03*
X36399Y1828750D03*
X26099Y1824950D03*
X25999Y1842550D03*
X46499Y1836550D03*
X47166Y1839884D03*
X80999Y1836550D03*
X90000Y1827900D03*
X43099Y1833850D03*
X39699D03*
X93500Y1827900D03*
X40500Y1863000D03*
X22367Y1836633D03*
X50299Y1946650D03*
X53999D03*
X42532Y1946783D03*
X44399Y1942250D03*
X38703Y1946754D03*
X34799Y1946750D03*
X46565Y1946703D03*
X44368Y1951450D03*
X45999Y1971450D03*
X28799Y1919060D03*
X14999Y1940050D03*
X15099Y1944050D03*
X50499Y1961550D03*
X14999Y1936050D03*
X17499Y1961050D03*
X43462Y1961160D03*
X32999Y1960555D03*
X23030Y1922038D03*
X25499Y1956050D03*
X42499Y1902550D03*
X48499Y1897050D03*
X26765Y1921945D03*
X57999Y1891050D03*
X31799Y1979050D03*
X112999Y124050D03*
X111790Y132259D03*
X152499Y149550D03*
X173499Y149050D03*
X175999Y82428D03*
X97499Y90050D03*
X115876Y125973D03*
Y130050D03*
X174999Y79050D03*
X175499Y86572D03*
X178999Y79050D03*
X176399Y94872D03*
X127999Y157050D03*
X114900Y177900D03*
X173500Y166315D03*
X154200Y168500D03*
X149400Y166400D03*
X149999Y243504D03*
Y239729D03*
X122397Y252688D03*
X122799Y249150D03*
X147099Y245350D03*
X124999Y246050D03*
X123300Y256000D03*
X157440Y283924D03*
Y303924D03*
Y313924D03*
X141499Y427550D03*
X165500Y416500D03*
X166500Y428500D03*
X153459Y427494D03*
X154101Y445550D03*
X141499Y423050D03*
X159600Y446399D03*
X152000Y520813D03*
X171722Y513827D03*
X163549Y517100D03*
X140940Y561800D03*
X150500Y545000D03*
X102100Y514900D03*
X163449Y521650D03*
X107526Y528996D03*
X104502Y530552D03*
X138999Y524213D03*
X173100Y483100D03*
X168453Y527949D03*
X160932Y549468D03*
X135499Y517550D03*
X107499Y497050D03*
X98900Y513400D03*
X172499Y491053D03*
X137899Y545451D03*
X176799Y493850D03*
X150750Y540416D03*
X109400Y543200D03*
X149000Y537500D03*
X106000Y543200D03*
X156500Y554000D03*
X138416Y553500D03*
X125499Y635550D03*
Y638950D03*
X127999Y645550D03*
X131400Y644600D03*
X144238Y645356D03*
X161000Y639100D03*
X124999Y643050D03*
X129000Y636600D03*
X128600Y640500D03*
X140900Y644000D03*
X134300Y646400D03*
X107000Y604800D03*
X105100Y600000D03*
X157000Y573851D03*
X141300Y565900D03*
X160824Y577000D03*
X144238Y649131D03*
X140400Y649800D03*
X158885Y679436D03*
Y689436D03*
X141500Y711000D03*
X158385Y719436D03*
X111200Y799450D03*
X110195Y809979D03*
X110500Y790200D03*
X110700Y795700D03*
X109831Y806598D03*
X109700Y803200D03*
X110202Y813379D03*
X154799Y838050D03*
X165499Y815550D03*
X110499Y834550D03*
X172660Y815731D03*
X174199Y841050D03*
X159500Y814700D03*
X169106Y815865D03*
X153900Y832200D03*
X98700Y842600D03*
Y822550D03*
X98000Y833500D03*
X163500Y937100D03*
X172500Y919294D03*
X108200Y963600D03*
X172000Y931600D03*
X106749Y934367D03*
X108441Y924705D03*
X160399Y922850D03*
X153499Y918550D03*
X108845Y931657D03*
X109099Y928250D03*
X171100Y935000D03*
X102100Y968500D03*
X99000Y965000D03*
X172000Y961000D03*
X152500Y960000D03*
X170250Y948500D03*
X154749Y968249D03*
X171000Y939500D03*
X123999Y1054050D03*
Y1050650D03*
X120100Y1053200D03*
X124100Y1047100D03*
X112699Y1058974D03*
X104600Y980500D03*
X154749Y979149D03*
X103200Y985364D03*
X104700Y989900D03*
X120749Y1093990D03*
X164700Y1085400D03*
X105499Y1080550D03*
X106718Y1076050D03*
X105999Y1085800D03*
X101499Y1072550D03*
X125900Y1091282D03*
X132499Y1094550D03*
X137100Y1084800D03*
X140800Y1076300D03*
X121500Y1083600D03*
X121100Y1075300D03*
X116249Y1102550D03*
X112999Y1103740D03*
X117499Y1079300D03*
X157700Y1114948D03*
X157600Y1124948D03*
X159000Y1083000D03*
X127000Y1113500D03*
X123999Y1102550D03*
X138600Y1124600D03*
X116700Y1063500D03*
X105600Y1069500D03*
X108999Y1102050D03*
X137481Y1077557D03*
X137477Y1081177D03*
X124423Y1077523D03*
Y1081177D03*
X106999Y1194550D03*
X102900Y1196050D03*
X103686Y1223863D03*
X103999Y1216863D03*
X127000Y1202000D03*
X148000Y1206000D03*
X106162Y1205702D03*
X114999Y1210363D03*
X130699Y1210653D03*
X118999Y1219050D03*
X123970Y1221573D03*
X119399Y1298113D03*
X101541Y1262607D03*
X116999Y1288050D03*
X101399Y1292550D03*
X107999Y1307713D03*
X120507Y1317050D03*
X116499Y1328013D03*
X120507Y1328096D03*
X135850Y1322250D03*
X143700Y1332500D03*
X101500Y1352000D03*
X113500D03*
X113000Y1341000D03*
X102000D03*
X107228Y1330552D03*
X107500Y1340500D03*
X110499Y1365050D03*
X109999Y1355050D03*
X138000Y1359025D03*
X111499Y1311800D03*
X125999Y1315550D03*
X132999Y1319550D03*
X142667Y1319218D03*
X149562Y1315987D03*
X133475Y1331200D03*
X112440Y1358196D03*
X112999Y1361550D03*
X97229Y1373337D03*
X97000Y1377600D03*
X109228Y1337090D03*
Y1333315D03*
X102700Y1321363D03*
X119499Y1339050D03*
X121000Y1364000D03*
X148024Y1333525D03*
X140000Y1332600D03*
X129000Y1356500D03*
X113500Y1344500D03*
Y1348154D03*
X102350Y1344500D03*
Y1348154D03*
X147400Y1321600D03*
X125100Y1366000D03*
X124290Y1469241D03*
X123808Y1465050D03*
X117390Y1426201D03*
Y1429976D03*
X104935Y1440634D03*
X142999Y1456373D03*
X104999Y1444941D03*
X106999Y1454450D03*
X100699Y1471050D03*
X139815Y1454438D03*
X139235Y1460973D03*
X123999Y1473050D03*
X127898Y1462441D03*
X107300Y1438100D03*
X114499Y1432050D03*
X114000Y1425400D03*
X107999Y1448050D03*
X150338Y1453958D03*
X152499Y1462940D03*
X105099Y1459150D03*
X142900Y1460000D03*
X100800Y1536450D03*
X98599Y1491350D03*
X157440Y1490460D03*
Y1500460D03*
Y1520460D03*
Y1530460D03*
X100499Y1479650D03*
X122199Y1476050D03*
X99899Y1539850D03*
X100000Y1546650D03*
X97499Y1554550D03*
X96999Y1558050D03*
X98144Y1534309D03*
X157400Y1596550D03*
X160200Y1598500D03*
X150999Y1713550D03*
X171999Y1662250D03*
X131999Y1710050D03*
X117499Y1706050D03*
X128749Y1703300D03*
X169100Y1685800D03*
X133090Y1699959D03*
X174250Y1694500D03*
X109499Y1712213D03*
X104999Y1708963D03*
X141500Y1715500D03*
X117249Y1712090D03*
X165575Y1676975D03*
X112753Y1716613D03*
X152633Y1677967D03*
X122642Y1704243D03*
X112562Y1720613D03*
X135499Y1710150D03*
X118499Y1694050D03*
X123749Y1711550D03*
X177900Y1690400D03*
X169600Y1682300D03*
X109499Y1743550D03*
X107300Y1746300D03*
X107100Y1736000D03*
X109399Y1739550D03*
X99199Y1761899D03*
X99999Y1753575D03*
X141999Y1764550D03*
X110099Y1759875D03*
X101399Y1784700D03*
X165900Y1790500D03*
X161900Y1793400D03*
X123393Y1870859D03*
X137999Y1861497D03*
Y1865151D03*
X123592Y1874254D03*
X96600Y1826000D03*
X135999Y1881550D03*
X141300Y1866400D03*
X141800Y1860500D03*
X97999Y1843050D03*
X159421Y1925972D03*
X210638Y62959D03*
X210634Y66863D03*
X201499Y104550D03*
X245499Y100550D03*
X246499Y86050D03*
Y80550D03*
X215138Y72559D03*
X210685Y74725D03*
X210605Y70692D03*
X205938Y72528D03*
X210738Y78459D03*
Y82159D03*
X186999Y99050D03*
X213499Y104650D03*
X223499Y108150D03*
X188999Y120800D03*
X205499Y105550D03*
X225499Y68550D03*
X233749Y110800D03*
X230749Y76300D03*
X207999Y109550D03*
X237899Y107050D03*
X197899Y165075D03*
X218499Y190550D03*
X247800Y269700D03*
X225298Y281114D03*
X213499Y283864D03*
X253871Y291410D03*
X250300Y275100D03*
X250400Y283100D03*
X239600Y278600D03*
X213400Y355300D03*
X224998Y357049D03*
X233998Y357549D03*
X239400Y357400D03*
X252935Y319114D03*
X214063Y318114D03*
X231800Y318414D03*
X179700Y425800D03*
X187699Y492850D03*
X199900Y554050D03*
X182499Y532550D03*
X220000Y516400D03*
X183499Y556100D03*
X188000Y484500D03*
X193549Y575875D03*
X246800Y677100D03*
X216999Y686550D03*
X213999Y725050D03*
X230849Y726050D03*
X252499D03*
X254499Y697700D03*
X249700Y682500D03*
X249800Y689900D03*
X238500Y680800D03*
X228999Y765550D03*
X218224Y765325D03*
X241600Y765700D03*
X236800Y765800D03*
X199000Y815000D03*
X200539Y890300D03*
X211750Y894600D03*
X198924Y975975D03*
X229562Y904113D03*
X215499Y905550D03*
X200799Y896600D03*
X233500Y1066100D03*
X226800Y1093400D03*
X221800Y1069300D03*
X247500Y1085500D03*
X256000Y1133000D03*
X255000Y1125700D03*
X221300Y1083238D03*
X251500Y1136700D03*
X229800Y1073600D03*
X242000Y1066000D03*
X182500Y1275500D03*
X199149Y1362900D03*
X194700Y1385700D03*
X181000Y1365500D03*
X180500Y1369900D03*
X229025Y1471576D03*
X241000Y1469600D03*
X224750Y1483950D03*
X232650Y1493450D03*
X233700Y1481600D03*
X199500Y1627000D03*
X195000Y1645500D03*
X179999Y1655887D03*
X186000Y1644000D03*
X179999Y1644500D03*
X181100Y1682700D03*
X194049Y1792600D03*
X201499Y1781050D03*
X227814Y1887513D03*
X231800Y1887100D03*
X236225Y1883125D03*
X229800Y1875700D03*
X218100Y1886400D03*
X213138Y1952703D03*
X249499Y1928050D03*
X231999Y1914050D03*
X210999Y1942050D03*
X223436Y1890465D03*
X232314Y1890513D03*
X213562Y1926113D03*
X220062Y1931113D03*
X240964Y1934113D03*
X214999Y1909550D03*
X257499Y1911050D03*
X249600Y1896800D03*
X343499Y60150D03*
X296099Y17100D03*
X305099Y17000D03*
X311400Y17100D03*
X317000Y17300D03*
X341499Y63050D03*
Y67110D03*
X343499Y31650D03*
X308999Y87050D03*
X323400Y105200D03*
X291999Y94050D03*
X282800Y87500D03*
X297499Y97550D03*
X315800Y100500D03*
X324800Y89400D03*
X293999Y293550D03*
X326499Y334054D03*
X284999Y338650D03*
X281499Y338550D03*
X313039Y352350D03*
X321900Y364600D03*
X298800Y333000D03*
X294500Y339000D03*
X326499Y337454D03*
X301249Y346050D03*
X344520Y406329D03*
X308999Y716450D03*
X315999Y718950D03*
X279939Y728610D03*
X329499Y801550D03*
X330540Y795509D03*
X327999Y740550D03*
X320499Y798050D03*
X285499Y745050D03*
X282099D03*
X292999Y743650D03*
X298000Y743500D03*
X323249Y749010D03*
X324959Y766750D03*
X277039Y740300D03*
X327749Y744050D03*
X306500Y753550D03*
X340699Y1046086D03*
X269500Y1135500D03*
X282500Y1135000D03*
X283499Y1556050D03*
X279999D03*
X289999Y1554650D03*
X293700Y1553351D03*
X276039Y1551300D03*
X314999Y1527550D03*
X326500Y1550200D03*
X261999Y1516050D03*
X295000Y1513000D03*
X333000Y1578000D03*
X297800Y1561600D03*
X291400Y1561500D03*
X324000Y1562500D03*
X312999Y1566050D03*
X323999Y1577250D03*
X330300Y1561200D03*
X310249Y1569800D03*
X264499Y1964050D03*
X331622Y1944767D03*
X288709Y1948042D03*
X284999Y1947691D03*
X342999Y1947409D03*
X342621Y1943409D03*
X330500Y1966500D03*
X280689Y1942710D03*
X315999Y1958550D03*
X327100Y1966472D03*
X329999Y1952273D03*
X325221Y1927272D03*
X313499Y1919050D03*
X332103Y1948133D03*
X310499Y1957050D03*
X285499Y1930050D03*
X381999Y57050D03*
X398799Y36152D03*
X381999Y50150D03*
X386799Y45000D03*
X381999Y53550D03*
X394199Y45050D03*
X358999Y61550D03*
X354999Y72050D03*
X426000Y93500D03*
X357503Y77043D03*
X374499Y77550D03*
X385999Y78050D03*
X401499Y80550D03*
X371700Y85500D03*
X400499Y406329D03*
X371999Y549300D03*
X394649Y630600D03*
X350499Y597300D03*
X375999Y698550D03*
X350499Y715050D03*
X371500Y880600D03*
X364499Y1099050D03*
X372999Y1123550D03*
X345499Y1096550D03*
X370149Y1320050D03*
X345424Y1310050D03*
X347324Y1524000D03*
X366149Y1554050D03*
X402499Y1476850D03*
X390999Y1514398D03*
Y1517798D03*
X349774Y1582900D03*
X354500Y1559500D03*
X400999Y1575550D03*
X354000Y1584900D03*
X353499Y1710450D03*
X377900Y1703800D03*
X348499Y1762050D03*
X385499Y1735050D03*
X367000Y1810000D03*
X360000Y1967500D03*
X645549Y1815134D03*
X644360Y1819137D03*
X659549Y1810634D03*
X757499Y745342D03*
Y1079550D03*
X755600Y1149800D03*
X758499Y1371050D03*
X757999Y1484050D03*
X754000Y1551000D03*
X750000Y1560500D03*
X732549Y1806634D03*
X733149Y1798634D03*
X690249Y1805634D03*
X707600Y1815600D03*
X733049Y1814134D03*
X755000Y1825000D03*
X711652Y1822109D03*
X711848Y1825504D03*
X758499Y1893550D03*
X752500Y1954500D03*
X821999Y193116D03*
X827499Y163550D03*
X820749Y163850D03*
X813249Y163800D03*
X839249Y164050D03*
X829917Y216200D03*
X833576Y215432D03*
X837999Y219550D03*
X822100Y279500D03*
X827500Y274500D03*
X770999Y302050D03*
X785499Y291050D03*
X770999Y290050D03*
Y295550D03*
X827499Y313424D03*
X763571Y295622D03*
X777999Y296050D03*
X786978Y298529D03*
X836500Y274950D03*
X812500Y282750D03*
X809940Y264940D03*
X822100Y261700D03*
X816700Y274300D03*
X791499Y333050D03*
X789999Y336550D03*
X772499Y323050D03*
X758778Y345000D03*
X768178Y333964D03*
X784499Y334050D03*
X772873Y326924D03*
X780499Y330050D03*
X771105Y722789D03*
X829800Y666650D03*
X835150Y677650D03*
X806500Y687250D03*
X781999Y725550D03*
X808660Y667540D03*
X820600Y664300D03*
X813200Y675900D03*
X788999Y736050D03*
X791999Y733050D03*
X766499Y732842D03*
X762500Y734000D03*
X784939Y733550D03*
X769999Y733050D03*
X792154Y1135926D03*
X825700Y1083100D03*
X771999Y1124550D03*
X767083Y1134550D03*
X764549Y1138500D03*
X784439Y1136550D03*
X814000Y1087000D03*
X772499Y1130050D03*
X789499Y1138050D03*
X779499Y1131050D03*
X807000Y1072900D03*
X825800Y1072300D03*
X815400Y1078800D03*
X803199Y1151850D03*
X822100Y1466800D03*
X774542Y1530050D03*
X804899Y1556950D03*
X827700Y1487600D03*
X836625Y1487400D03*
X771225Y1539474D03*
X767936Y1540336D03*
X784577Y1535628D03*
X812550Y1494050D03*
X774577Y1533796D03*
X791499Y1543550D03*
X793999Y1541050D03*
X784499Y1529050D03*
X809960Y1478040D03*
X814700Y1486300D03*
X788000Y1788000D03*
X774500D03*
X812000Y1799500D03*
X821249Y1791250D03*
X811000Y1793000D03*
X793000Y1803500D03*
X795849Y1805500D03*
X828500Y1877800D03*
X770999Y1820550D03*
X822499Y1815164D03*
X791999Y1819050D03*
X783499Y1827050D03*
X807000Y1822300D03*
X803500Y1822708D03*
X810900Y1882440D03*
X822700Y1871100D03*
X805900Y1887560D03*
X771499Y1936550D03*
X802499Y1951550D03*
X800431Y1941193D03*
X767999Y1945173D03*
X764908Y1946592D03*
X785939Y1946800D03*
X812500Y1898500D03*
X771499Y1940050D03*
X802099Y1961950D03*
X834799Y1946950D03*
X792499Y1949050D03*
X794499Y1941050D03*
X782999Y1937050D03*
X919800Y54600D03*
X924200Y69800D03*
X898800Y96000D03*
X855500Y149500D03*
X873000Y148500D03*
X846500Y149500D03*
X841499Y135550D03*
X861999Y146550D03*
X882499Y147050D03*
X896999Y141550D03*
X916499Y115050D03*
X923761Y85550D03*
X907499Y131800D03*
X902499Y110550D03*
X901499Y92050D03*
X898999Y110550D03*
X897555Y90494D03*
X910999Y124550D03*
X916499Y172550D03*
X867500Y163924D03*
X867576Y159924D03*
X878078Y240103D03*
Y243878D03*
X854400Y264600D03*
X847878Y250040D03*
X851278Y249974D03*
X842499Y280924D03*
X847500Y246600D03*
X850999Y246550D03*
X874700Y244900D03*
X874900Y238600D03*
X871999Y283924D03*
X886200Y313924D03*
X886600Y303924D03*
X872136Y273924D03*
X858478Y274050D03*
X868799Y294750D03*
X865499Y288050D03*
X867899Y321550D03*
X868299Y336150D03*
X902999Y556050D03*
X878596Y645573D03*
X875100Y644400D03*
X922049Y574375D03*
X879750Y570550D03*
X879950Y565050D03*
X851172Y655432D03*
X878596Y649348D03*
X847772Y655370D03*
X875300Y650500D03*
X851300Y651700D03*
X847600Y651600D03*
X852696Y671197D03*
X922049Y978575D03*
X900499Y962100D03*
X879708Y971892D03*
X878233Y1051095D03*
X877964Y1054485D03*
X850833Y1061441D03*
X847233Y1061492D03*
X847500Y1057800D03*
X851000Y1058000D03*
X874733Y1055792D03*
X874999Y1049550D03*
X900999Y979050D03*
X883083Y979183D03*
X864499Y1128750D03*
X852333Y1077716D03*
X871499Y1124948D03*
X872086Y1114948D03*
X871999Y1094948D03*
X872086Y1084948D03*
X860133Y1084142D03*
X860799Y1358925D03*
X861849Y1376050D03*
X866700Y1379796D03*
X866596Y1375796D03*
X848888Y1466402D03*
X852288Y1466346D03*
X878054Y1456450D03*
X877853Y1459991D03*
X874100Y1461600D03*
X874900Y1454000D03*
X848861Y1462463D03*
X852500Y1462600D03*
X867523Y1542821D03*
X867199Y1535150D03*
X854327Y1477550D03*
X858827Y1485696D03*
X872086Y1490460D03*
X871999Y1500460D03*
Y1520460D03*
X872086Y1530460D03*
X863699Y1501250D03*
X900500Y1721500D03*
X886439Y1717600D03*
X862800Y1712700D03*
X889800Y1711500D03*
X921549Y1788475D03*
X917499Y1796550D03*
X879700Y1786300D03*
X873300Y1740100D03*
X879664Y1782213D03*
X866914Y1861840D03*
X853499Y1871036D03*
X866914Y1865615D03*
X850099Y1871056D03*
X851500Y1821400D03*
X849375Y1824982D03*
X854905Y1825583D03*
X854480Y1867578D03*
X849999Y1867550D03*
X863700Y1867300D03*
X865300Y1858700D03*
X854814Y1883550D03*
X859314Y1891365D03*
X871921Y1905972D03*
X871421Y1895972D03*
X872086Y1925972D03*
Y1935972D03*
X863699Y1906450D03*
X857099Y1917650D03*
X961499Y100050D03*
X946899Y122550D03*
X932961Y85581D03*
X928461Y75981D03*
X928561Y91481D03*
X928508Y87747D03*
X928428Y83714D03*
X928561Y95181D03*
X928457Y79885D03*
X958999Y96050D03*
X930999Y115550D03*
X937999Y122050D03*
X938499Y115550D03*
X961499Y93350D03*
X926999Y122050D03*
X943499Y82550D03*
X934499Y118750D03*
X926999Y115050D03*
X939549Y175175D03*
X966499Y552050D03*
X965999Y954550D03*
X986400Y1639302D03*
X987100Y1624900D03*
X981200Y1625800D03*
X990425Y1633898D03*
X987029Y1634075D03*
X981200Y1618002D03*
X964000Y1639200D03*
X960900Y1636400D03*
X969600Y1638300D03*
X977500Y1660500D03*
X978000Y1668000D03*
X967600Y1651100D03*
X989502Y1646000D03*
X988800Y1658300D03*
X989000Y1663802D03*
X987200Y1675600D03*
X989900Y1678800D03*
X974000Y1670700D03*
X984211Y1667500D03*
X971558Y1646500D03*
X981500Y1653000D03*
X980800Y1659600D03*
X982050Y1649302D03*
G54D24*
G01X23499Y1381500D02*
Y1382601D01*
G54D15*
X17720Y1903144D03*
X29532Y309561D03*
Y1029522D03*
X129920Y17716D03*
X271657Y267711D03*
Y673223D03*
Y1078734D03*
Y1484246D03*
Y1889758D03*
X994098Y149601D03*
Y673223D03*
X994099Y1068892D03*
X994093Y1889751D03*
G54D25*
G01X12380Y309561D02*
X29532D01*
G01X68898Y12645D02*
Y17047D01*
G01D02*
Y21449D01*
G01X62346Y17047D02*
X68898D01*
G01D02*
X75450D01*
G01X68898Y185873D02*
Y190275D01*
G01D02*
Y194677D01*
G01Y190275D02*
X75450D01*
G01X29532Y292409D02*
Y309561D01*
G01D02*
Y326713D01*
G01Y309561D02*
X46684D01*
G01X68898Y418157D02*
Y422559D01*
G01D02*
Y426961D01*
G01X62346Y422559D02*
X68898D01*
G01D02*
X75450D01*
G01X68898Y1634693D02*
Y1639095D01*
G01D02*
Y1643497D01*
G01Y1639095D02*
X75450D01*
G01X17720Y1885992D02*
Y1903144D01*
G01D02*
Y1920296D01*
G01X129920Y17716D02*
Y34868D01*
G01X112768Y17716D02*
X129920D01*
G01D02*
X147072D01*
G01X167323Y175401D02*
Y179803D01*
G01D02*
Y184205D01*
G01X160771Y179803D02*
X167323D01*
G01D02*
X173875D01*
G01X167323Y348629D02*
Y353031D01*
G01D02*
Y357433D01*
G01X160771Y353031D02*
X167323D01*
G01D02*
X173875D01*
G01X167323Y580913D02*
Y585315D01*
G01D02*
Y589717D01*
G01X160771Y585315D02*
X167323D01*
G01D02*
X173875D01*
G01X167323Y754141D02*
Y758543D01*
G01D02*
Y762945D01*
G01X160771Y758543D02*
X167323D01*
G01D02*
X173875D01*
G01X167323Y1565165D02*
Y1569567D01*
G01D02*
Y1573969D01*
G01X160771Y1569567D02*
X167323D01*
G01D02*
X173875D01*
G01X167323Y1797449D02*
Y1801851D01*
G01D02*
Y1806253D01*
G01X160771Y1801851D02*
X167323D01*
G01D02*
X173875D01*
G01X167323Y1970677D02*
Y1975079D01*
G01D02*
Y1979481D01*
G01X160771Y1975079D02*
X167323D01*
G01D02*
X173875D01*
G01X254505Y267711D02*
X271657D01*
G01X254505Y673223D02*
X271657D01*
G01X254505Y1078734D02*
X271657D01*
G01X254505Y1484246D02*
X271657D01*
G01X254505Y1889758D02*
X271657D01*
G01Y250559D02*
Y267711D01*
G01D02*
Y284863D01*
G01Y267711D02*
X288809D01*
G01X271657Y656071D02*
Y673223D01*
G01D02*
Y690375D01*
G01Y673223D02*
X288809D01*
G01X271657Y1061582D02*
Y1078734D01*
G01D02*
Y1095886D01*
G01Y1078734D02*
X288809D01*
G01X271657Y1467094D02*
Y1484246D01*
G01D02*
Y1501398D01*
G01Y1484246D02*
X288809D01*
G01X271657Y1872606D02*
Y1889758D01*
G01D02*
Y1906910D01*
G01X895669Y175401D02*
Y179803D01*
G01D02*
Y184205D01*
G01X889117Y179803D02*
X895669D01*
G01D02*
X902221D01*
G01X895669Y348629D02*
Y353031D01*
G01D02*
Y357433D01*
G01X889117Y353031D02*
X895669D01*
G01D02*
X902221D01*
G01X895669Y580913D02*
Y585315D01*
G01D02*
Y589717D01*
G01X889117Y585315D02*
X895669D01*
G01D02*
X902221D01*
G01X895669Y754141D02*
Y758543D01*
G01D02*
Y762945D01*
G01X889117Y758543D02*
X895669D01*
G01D02*
X902221D01*
G01X895669Y986425D02*
Y990827D01*
G01D02*
Y995229D01*
G01X889117Y990827D02*
X895669D01*
G01D02*
X902221D01*
G01X895669Y1159653D02*
Y1164055D01*
G01D02*
Y1168457D01*
G01X889117Y1164055D02*
X895669D01*
G01D02*
X902221D01*
G01X895669Y1391937D02*
Y1396339D01*
G01D02*
Y1400741D01*
G01X889117Y1396339D02*
X895669D01*
G01D02*
X902221D01*
G01X895669Y1565165D02*
Y1569567D01*
G01D02*
Y1573969D01*
G01X889117Y1569567D02*
X895669D01*
G01D02*
X902221D01*
G01X895669Y1797449D02*
Y1801851D01*
G01D02*
Y1806253D01*
G01X889117Y1801851D02*
X895669D01*
G01D02*
X902221D01*
G01X895669Y1970677D02*
Y1975079D01*
G01D02*
Y1979481D01*
G01X889117Y1975079D02*
X895669D01*
G01D02*
X902221D01*
G01X994098Y132449D02*
Y149601D01*
G01D02*
Y166753D01*
G01X976946Y149601D02*
X994098D01*
G01D02*
X1011250D01*
G01X994098Y656071D02*
Y673223D01*
G01D02*
Y690375D01*
G01X976946Y673223D02*
X994098D01*
G01D02*
X1011250D01*
G01X994099Y1051740D02*
Y1068892D01*
G01D02*
Y1086044D01*
G01X976947Y1068892D02*
X994099D01*
G01D02*
X1011251D01*
G01X994093Y1872599D02*
Y1889751D01*
G01D02*
Y1906903D01*
G01X976941Y1889751D02*
X994093D01*
G01D02*
X1011245D01*
G54D16*
X68898Y17047D03*
Y190275D03*
Y422559D03*
Y595787D03*
Y828071D03*
Y1001299D03*
Y1233583D03*
Y1406811D03*
Y1639095D03*
Y1812323D03*
X167323Y179803D03*
Y353031D03*
Y585315D03*
Y758543D03*
Y990827D03*
Y1164055D03*
Y1396339D03*
Y1569567D03*
Y1801851D03*
Y1975079D03*
X895669Y179803D03*
Y353031D03*
Y585315D03*
Y758543D03*
Y990827D03*
Y1164055D03*
Y1396339D03*
Y1569567D03*
Y1801851D03*
Y1975079D03*
G54D26*
G01X-89222Y-207897D02*
Y-190397D01*
G01X-80052D02*
Y-207897D01*
G01Y-199147D02*
X-89222D01*
G01X-67137Y-207897D02*
X-68447Y-207605D01*
X-69757Y-206439D01*
X-70631Y-204397D01*
X-71067Y-202064D01*
X-70631Y-199730D01*
X-69757Y-197689D01*
X-68447Y-196522D01*
X-67137Y-196231D01*
X-65827Y-196522D01*
X-64517Y-197689D01*
X-63644Y-199730D01*
X-63425Y-202064D01*
X-63644Y-204397D01*
X-64517Y-206439D01*
X-65827Y-207605D01*
X-67137Y-207897D01*
G01X-53349D02*
Y-196231D01*
G01Y-199147D02*
X-52475Y-197689D01*
X-51165Y-196522D01*
X-49419Y-196231D01*
X-47891Y-196522D01*
X-46580Y-197689D01*
X-45925Y-199730D01*
Y-207897D01*
G01X-35412Y-200022D02*
X-28425D01*
X-29080Y-197980D01*
X-30172Y-196814D01*
X-31700Y-196231D01*
X-33229Y-196522D01*
X-34539Y-197397D01*
X-35412Y-199439D01*
X-35849Y-201189D01*
Y-202939D01*
X-35412Y-204689D01*
X-34320Y-206439D01*
X-33010Y-207605D01*
X-31482Y-207897D01*
X-29954Y-207314D01*
X-28425Y-205564D01*
G01X-19222Y-213147D02*
X-17912Y-213730D01*
X-16165Y-213147D01*
X-15074Y-211981D01*
X-14200Y-210522D01*
X-12891Y-205856D01*
X-10052Y-196231D01*
G01X-17039D02*
X-12891Y-205856D01*
G01X22109Y-198564D02*
X22983Y-197689D01*
X23638Y-196231D01*
X24075Y-194188D01*
X23638Y-192439D01*
X22765Y-191272D01*
X21236Y-190397D01*
X15341D01*
Y-207897D01*
X22546D01*
X24075Y-206731D01*
X24948Y-204980D01*
X25385Y-202939D01*
X24948Y-200897D01*
X23638Y-199147D01*
X22109Y-198564D01*
X15341D01*
G01X41793Y-207897D02*
Y-196231D01*
G01Y-198272D02*
X40920Y-197106D01*
X39609Y-196522D01*
X38081Y-196231D01*
X36553Y-196814D01*
X35243Y-197980D01*
X34369Y-199730D01*
X33933Y-202064D01*
X34369Y-204397D01*
X35243Y-206147D01*
X36553Y-207314D01*
X38081Y-207897D01*
X39609Y-207605D01*
X40920Y-206731D01*
X41793Y-205564D01*
G01X59293Y-190397D02*
Y-207897D01*
G01Y-205273D02*
X58420Y-206731D01*
X57109Y-207605D01*
X55581Y-207897D01*
X53835Y-207314D01*
X52525Y-205856D01*
X51651Y-204106D01*
X51433Y-202064D01*
X51651Y-200022D01*
X52525Y-198272D01*
X53835Y-196814D01*
X55581Y-196231D01*
X57109Y-196522D01*
X58201Y-197106D01*
X59293Y-198272D01*
G01X69806Y-212272D02*
X71335Y-213439D01*
X73081Y-213730D01*
X74609Y-213439D01*
X75920Y-211981D01*
X76793Y-209939D01*
Y-196231D01*
G01Y-198564D02*
X75920Y-197397D01*
X74609Y-196522D01*
X73081Y-196231D01*
X71335Y-196814D01*
X70243Y-197980D01*
X69369Y-200022D01*
X68933Y-202064D01*
X69151Y-203814D01*
X70025Y-205856D01*
X71335Y-207314D01*
X73081Y-207897D01*
X74391Y-207605D01*
X75920Y-206439D01*
X76793Y-205273D01*
G01X87088Y-200022D02*
X94075D01*
X93420Y-197980D01*
X92328Y-196814D01*
X90800Y-196231D01*
X89271Y-196522D01*
X87961Y-197397D01*
X87088Y-199439D01*
X86651Y-201189D01*
Y-202939D01*
X87088Y-204689D01*
X88180Y-206439D01*
X89490Y-207605D01*
X91018Y-207897D01*
X92546Y-207314D01*
X94075Y-205564D01*
G01X104806Y-207897D02*
Y-196231D01*
G01Y-198564D02*
X105898Y-197397D01*
X106990Y-196522D01*
X108518Y-196231D01*
X109609Y-196522D01*
X110920Y-197397D01*
G01X138060Y-207897D02*
Y-190397D01*
X142426D01*
X144173Y-191272D01*
X145483Y-192439D01*
X146575Y-194188D01*
X147448Y-196231D01*
X147666Y-199147D01*
X147448Y-202064D01*
X146575Y-204106D01*
X145483Y-205856D01*
X144173Y-207022D01*
X142426Y-207897D01*
X138060D01*
G01X155996D02*
Y-190397D01*
X161236D01*
X162983Y-191272D01*
X164293Y-193314D01*
X164730Y-195647D01*
X164293Y-197980D01*
X163201Y-199730D01*
X161236Y-200606D01*
X155996D01*
G01X179609Y-198564D02*
X180483Y-197689D01*
X181138Y-196231D01*
X181575Y-194188D01*
X181138Y-192439D01*
X180265Y-191272D01*
X178736Y-190397D01*
X172841D01*
Y-207897D01*
X180046D01*
X181575Y-206731D01*
X182448Y-204980D01*
X182885Y-202939D01*
X182448Y-200897D01*
X181138Y-199147D01*
X179609Y-198564D01*
X172841D01*
G01X208496Y-190397D02*
Y-207897D01*
X217230D01*
G01X230363D02*
X229053Y-207605D01*
X227743Y-206439D01*
X226869Y-204397D01*
X226433Y-202064D01*
X226869Y-199730D01*
X227743Y-197689D01*
X229053Y-196522D01*
X230363Y-196231D01*
X231673Y-196522D01*
X232983Y-197689D01*
X233856Y-199730D01*
X234075Y-202064D01*
X233856Y-204397D01*
X232983Y-206439D01*
X231673Y-207605D01*
X230363Y-207897D01*
G01X242404Y-196231D02*
X245025Y-207897D01*
X247863Y-196231D01*
X250701Y-207897D01*
X253322Y-196231D01*
G01X278496Y-190397D02*
Y-207897D01*
X287230D01*
G01X300363D02*
X299053Y-207605D01*
X297743Y-206439D01*
X296869Y-204397D01*
X296433Y-202064D01*
X296869Y-199730D01*
X297743Y-197689D01*
X299053Y-196522D01*
X300363Y-196231D01*
X301673Y-196522D01*
X302983Y-197689D01*
X303856Y-199730D01*
X304075Y-202064D01*
X303856Y-204397D01*
X302983Y-206439D01*
X301673Y-207605D01*
X300363Y-207897D01*
G01X314588Y-205856D02*
X315680Y-207022D01*
X317208Y-207897D01*
X318518D01*
X319828Y-207314D01*
X320701Y-206439D01*
X321138Y-205273D01*
X320920Y-203522D01*
X320046Y-202647D01*
X316116Y-200897D01*
X315243Y-198855D01*
X315680Y-197397D01*
X316553Y-196522D01*
X317863Y-196231D01*
X319173Y-196522D01*
X320483Y-197397D01*
G01X332088Y-205856D02*
X333180Y-207022D01*
X334708Y-207897D01*
X336018D01*
X337328Y-207314D01*
X338201Y-206439D01*
X338638Y-205273D01*
X338420Y-203522D01*
X337546Y-202647D01*
X333616Y-200897D01*
X332743Y-198855D01*
X333180Y-197397D01*
X334053Y-196522D01*
X335363Y-196231D01*
X336673Y-196522D01*
X337983Y-197397D01*
G01X94686Y-164897D02*
Y-147397D01*
X100363Y-161980D01*
X106040Y-147397D01*
Y-164897D01*
G01X117863D02*
X116553Y-164605D01*
X115243Y-163439D01*
X114369Y-161397D01*
X113933Y-159064D01*
X114369Y-156730D01*
X115243Y-154689D01*
X116553Y-153522D01*
X117863Y-153231D01*
X119173Y-153522D01*
X120483Y-154689D01*
X121356Y-156730D01*
X121575Y-159064D01*
X121356Y-161397D01*
X120483Y-163439D01*
X119173Y-164605D01*
X117863Y-164897D01*
G01X139293Y-147397D02*
Y-164897D01*
G01Y-162273D02*
X138420Y-163731D01*
X137109Y-164605D01*
X135581Y-164897D01*
X133835Y-164314D01*
X132525Y-162856D01*
X131651Y-161106D01*
X131433Y-159064D01*
X131651Y-157022D01*
X132525Y-155272D01*
X133835Y-153814D01*
X135581Y-153231D01*
X137109Y-153522D01*
X138201Y-154106D01*
X139293Y-155272D01*
G01X149588Y-157022D02*
X156575D01*
X155920Y-154980D01*
X154828Y-153814D01*
X153300Y-153231D01*
X151771Y-153522D01*
X150461Y-154397D01*
X149588Y-156439D01*
X149151Y-158189D01*
Y-159939D01*
X149588Y-161689D01*
X150680Y-163439D01*
X151990Y-164605D01*
X153518Y-164897D01*
X155046Y-164314D01*
X156575Y-162564D01*
G01X170363Y-164897D02*
Y-147397D01*
G01X376163Y-209897D02*
Y-192397D01*
X373543Y-195897D01*
G01Y-209897D02*
X378783D01*
G01X396283D02*
Y-192397D01*
X388204Y-204939D01*
X399122D01*
G01X406360Y-207273D02*
X407669Y-208731D01*
X409198Y-209605D01*
X411163Y-209897D01*
X413128Y-209314D01*
X414656Y-208147D01*
X415748Y-206106D01*
X415966Y-203772D01*
X415530Y-201439D01*
X414438Y-199980D01*
X412909Y-198814D01*
X411381Y-198522D01*
X409853Y-198814D01*
X407888Y-199980D01*
X408543Y-192397D01*
X414438D01*
G01X431283Y-209897D02*
Y-192397D01*
X423204Y-204939D01*
X434122D01*
G01X441360Y-207273D02*
X442669Y-208731D01*
X444198Y-209605D01*
X446163Y-209897D01*
X448128Y-209314D01*
X449656Y-208147D01*
X450748Y-206106D01*
X450966Y-203772D01*
X450530Y-201439D01*
X449438Y-199980D01*
X447909Y-198814D01*
X446381Y-198522D01*
X444853Y-198814D01*
X442888Y-199980D01*
X443543Y-192397D01*
X449438D01*
G01X363046Y-164897D02*
Y-147397D01*
X368286D01*
X370033Y-148272D01*
X371343Y-150314D01*
X371780Y-152647D01*
X371343Y-154980D01*
X370251Y-156730D01*
X368286Y-157606D01*
X363046D01*
G01X389716Y-148856D02*
X388406Y-147980D01*
X386878Y-147397D01*
X385131D01*
X383166Y-148272D01*
X381638Y-149730D01*
X380546Y-151481D01*
X379673Y-154397D01*
X379454Y-157022D01*
X379891Y-159647D01*
X380546Y-161397D01*
X381856Y-163147D01*
X383385Y-164314D01*
X384913Y-164897D01*
X386441D01*
X387970Y-164314D01*
X389280Y-163439D01*
X390372Y-162273D01*
G01X404159Y-155564D02*
X405033Y-154689D01*
X405688Y-153231D01*
X406125Y-151188D01*
X405688Y-149439D01*
X404815Y-148272D01*
X403286Y-147397D01*
X397391D01*
Y-164897D01*
X404596D01*
X406125Y-163731D01*
X406998Y-161980D01*
X407435Y-159939D01*
X406998Y-157897D01*
X405688Y-156147D01*
X404159Y-155564D01*
X397391D01*
G01X413363Y-170730D02*
X426463D01*
G01X432391Y-164897D02*
Y-147397D01*
X442435Y-164897D01*
Y-147397D01*
G01X454913Y-164897D02*
X453166Y-164605D01*
X451638Y-163439D01*
X450328Y-161689D01*
X449454Y-159647D01*
X449018Y-157314D01*
Y-154980D01*
X449454Y-152647D01*
X450328Y-150605D01*
X451638Y-148856D01*
X453166Y-147689D01*
X454913Y-147397D01*
X456659Y-147689D01*
X458188Y-148856D01*
X459498Y-150605D01*
X460372Y-152647D01*
X460808Y-154980D01*
Y-157314D01*
X460372Y-159647D01*
X459498Y-161689D01*
X458188Y-163439D01*
X456659Y-164605D01*
X454913Y-164897D01*
G01X505754Y-147397D02*
X511213Y-164897D01*
X516672Y-147397D01*
G01X533080Y-164897D02*
X524346D01*
Y-147397D01*
X533080D01*
G01X529586Y-155855D02*
X524346D01*
G01X541846Y-164897D02*
Y-147397D01*
X547305D01*
X549051Y-148272D01*
X550143Y-149439D01*
X550580Y-151772D01*
X550143Y-154106D01*
X548833Y-155564D01*
X547305Y-156439D01*
X541846D01*
G01X547305D02*
X550580Y-164897D01*
G01X563713Y-165480D02*
X563276Y-165189D01*
Y-164605D01*
X563713Y-164314D01*
X564150Y-164605D01*
Y-165189D01*
X563713Y-165480D01*
G01X524128Y-207564D02*
X525875Y-209022D01*
X527840Y-209897D01*
X529586D01*
X531333Y-209022D01*
X532643Y-207564D01*
X533298Y-205522D01*
X532861Y-203481D01*
X531770Y-201730D01*
X529805Y-200564D01*
X527185Y-199980D01*
X525656Y-198814D01*
X525001Y-196772D01*
X525438Y-194730D01*
X526530Y-193272D01*
X528058Y-192397D01*
X529586D01*
X531115Y-192980D01*
X532425Y-194439D01*
G01X540754Y-209897D02*
X546213Y-192397D01*
X551672Y-209897D01*
G01X549706Y-203772D02*
X542719D01*
G01X691780Y-192397D02*
Y-209897D01*
X683046D01*
G01X669913D02*
X668385Y-209605D01*
X666638Y-208731D01*
X665546Y-207273D01*
X665110Y-205230D01*
X665546Y-203189D01*
X666856Y-201439D01*
X668821Y-200564D01*
X671005D01*
X672315Y-199980D01*
X673407Y-198522D01*
X673843Y-196481D01*
X673188Y-194439D01*
X671660Y-192980D01*
X669913Y-192397D01*
X668167Y-192980D01*
X666638Y-194439D01*
X665983Y-196481D01*
X666420Y-198522D01*
X667511Y-199980D01*
X668821Y-200564D01*
X671005D01*
X672970Y-201439D01*
X674280Y-203189D01*
X674716Y-205230D01*
X674280Y-207273D01*
X673188Y-208731D01*
X671441Y-209605D01*
X669913Y-209897D01*
G01X630546Y-147397D02*
Y-164897D01*
X639280D01*
G01X656343D02*
Y-153231D01*
G01Y-155272D02*
X655470Y-154106D01*
X654159Y-153522D01*
X652631Y-153231D01*
X651103Y-153814D01*
X649793Y-154980D01*
X648919Y-156730D01*
X648483Y-159064D01*
X648919Y-161397D01*
X649793Y-163147D01*
X651103Y-164314D01*
X652631Y-164897D01*
X654159Y-164605D01*
X655470Y-163731D01*
X656343Y-162564D01*
G01X665328Y-170147D02*
X666638Y-170730D01*
X668385Y-170147D01*
X669476Y-168981D01*
X670350Y-167522D01*
X671659Y-162856D01*
X674498Y-153231D01*
G01X667511D02*
X671659Y-162856D01*
G01X684138Y-157022D02*
X691125D01*
X690470Y-154980D01*
X689378Y-153814D01*
X687850Y-153231D01*
X686321Y-153522D01*
X685011Y-154397D01*
X684138Y-156439D01*
X683701Y-158189D01*
Y-159939D01*
X684138Y-161689D01*
X685230Y-163439D01*
X686540Y-164605D01*
X688068Y-164897D01*
X689596Y-164314D01*
X691125Y-162564D01*
G01X701856Y-164897D02*
Y-153231D01*
G01Y-155564D02*
X702948Y-154397D01*
X704040Y-153522D01*
X705568Y-153231D01*
X706659Y-153522D01*
X707970Y-154397D01*
G01X719138Y-162856D02*
X720230Y-164022D01*
X721758Y-164897D01*
X723068D01*
X724378Y-164314D01*
X725251Y-163439D01*
X725688Y-162273D01*
X725470Y-160522D01*
X724596Y-159647D01*
X720666Y-157897D01*
X719793Y-155855D01*
X720230Y-154397D01*
X721103Y-153522D01*
X722413Y-153231D01*
X723723Y-153522D01*
X725033Y-154397D01*
G01X790596Y-209897D02*
Y-192397D01*
X796055D01*
X797801Y-193272D01*
X798893Y-194439D01*
X799330Y-196772D01*
X798893Y-199106D01*
X797583Y-200564D01*
X796055Y-201439D01*
X790596D01*
G01X796055D02*
X799330Y-209897D01*
G01X809188Y-202022D02*
X816175D01*
X815520Y-199980D01*
X814428Y-198814D01*
X812900Y-198231D01*
X811371Y-198522D01*
X810061Y-199397D01*
X809188Y-201439D01*
X808751Y-203189D01*
Y-204939D01*
X809188Y-206689D01*
X810280Y-208439D01*
X811590Y-209605D01*
X813118Y-209897D01*
X814646Y-209314D01*
X816175Y-207564D01*
G01X826033Y-209897D02*
Y-192397D01*
G01Y-201147D02*
X827125Y-199397D01*
X828435Y-198522D01*
X829745Y-198231D01*
X831709Y-198814D01*
X833020Y-199980D01*
X833893Y-202022D01*
Y-204355D01*
X833456Y-206689D01*
X832583Y-208439D01*
X831055Y-209605D01*
X829745Y-209897D01*
X828435Y-209605D01*
X827125Y-208731D01*
X826033Y-207273D01*
G01X844188Y-202022D02*
X851175D01*
X850520Y-199980D01*
X849428Y-198814D01*
X847900Y-198231D01*
X846371Y-198522D01*
X845061Y-199397D01*
X844188Y-201439D01*
X843751Y-203189D01*
Y-204939D01*
X844188Y-206689D01*
X845280Y-208439D01*
X846590Y-209605D01*
X848118Y-209897D01*
X849646Y-209314D01*
X851175Y-207564D01*
G01X868456Y-199689D02*
X866928Y-198522D01*
X865618Y-198231D01*
X863871Y-198814D01*
X862561Y-199980D01*
X861688Y-202022D01*
X861469Y-204064D01*
X861688Y-206106D01*
X862561Y-207856D01*
X863871Y-209314D01*
X865618Y-209897D01*
X867146Y-209314D01*
X868456Y-208147D01*
G01X885956Y-199689D02*
X884428Y-198522D01*
X883118Y-198231D01*
X881371Y-198814D01*
X880061Y-199980D01*
X879188Y-202022D01*
X878969Y-204064D01*
X879188Y-206106D01*
X880061Y-207856D01*
X881371Y-209314D01*
X883118Y-209897D01*
X884646Y-209314D01*
X885956Y-208147D01*
G01X903893Y-209897D02*
Y-198231D01*
G01Y-200272D02*
X903020Y-199106D01*
X901709Y-198522D01*
X900181Y-198231D01*
X898653Y-198814D01*
X897343Y-199980D01*
X896469Y-201730D01*
X896033Y-204064D01*
X896469Y-206397D01*
X897343Y-208147D01*
X898653Y-209314D01*
X900181Y-209897D01*
X901709Y-209605D01*
X903020Y-208731D01*
X903893Y-207564D01*
G01X781410Y-164897D02*
Y-147397D01*
X785776D01*
X787523Y-148272D01*
X788833Y-149439D01*
X789925Y-151188D01*
X790798Y-153231D01*
X791016Y-156147D01*
X790798Y-159064D01*
X789925Y-161106D01*
X788833Y-162856D01*
X787523Y-164022D01*
X785776Y-164897D01*
X781410D01*
G01X800438Y-157022D02*
X807425D01*
X806770Y-154980D01*
X805678Y-153814D01*
X804150Y-153231D01*
X802621Y-153522D01*
X801311Y-154397D01*
X800438Y-156439D01*
X800001Y-158189D01*
Y-159939D01*
X800438Y-161689D01*
X801530Y-163439D01*
X802840Y-164605D01*
X804368Y-164897D01*
X805896Y-164314D01*
X807425Y-162564D01*
G01X817938Y-162856D02*
X819030Y-164022D01*
X820558Y-164897D01*
X821868D01*
X823178Y-164314D01*
X824051Y-163439D01*
X824488Y-162273D01*
X824270Y-160522D01*
X823396Y-159647D01*
X819466Y-157897D01*
X818593Y-155855D01*
X819030Y-154397D01*
X819903Y-153522D01*
X821213Y-153231D01*
X822523Y-153522D01*
X823833Y-154397D01*
G01X838713Y-153231D02*
Y-164897D01*
G01Y-148564D02*
X838276Y-148272D01*
Y-147689D01*
X838713Y-147397D01*
X839150Y-147689D01*
Y-148272D01*
X838713Y-148564D01*
G01X853156Y-169272D02*
X854685Y-170439D01*
X856431Y-170730D01*
X857959Y-170439D01*
X859270Y-168981D01*
X860143Y-166939D01*
Y-153231D01*
G01Y-155564D02*
X859270Y-154397D01*
X857959Y-153522D01*
X856431Y-153231D01*
X854685Y-153814D01*
X853593Y-154980D01*
X852719Y-157022D01*
X852283Y-159064D01*
X852501Y-160814D01*
X853375Y-162856D01*
X854685Y-164314D01*
X856431Y-164897D01*
X857741Y-164605D01*
X859270Y-163439D01*
X860143Y-162273D01*
G01X870001Y-164897D02*
Y-153231D01*
G01Y-156147D02*
X870875Y-154689D01*
X872185Y-153522D01*
X873931Y-153231D01*
X875459Y-153522D01*
X876770Y-154689D01*
X877425Y-156730D01*
Y-164897D01*
G01X887938Y-157022D02*
X894925D01*
X894270Y-154980D01*
X893178Y-153814D01*
X891650Y-153231D01*
X890121Y-153522D01*
X888811Y-154397D01*
X887938Y-156439D01*
X887501Y-158189D01*
Y-159939D01*
X887938Y-161689D01*
X889030Y-163439D01*
X890340Y-164605D01*
X891868Y-164897D01*
X893396Y-164314D01*
X894925Y-162564D01*
G01X905656Y-164897D02*
Y-153231D01*
G01Y-155564D02*
X906748Y-154397D01*
X907840Y-153522D01*
X909368Y-153231D01*
X910459Y-153522D01*
X911770Y-154397D01*
G01X952413Y-192397D02*
X950666Y-192980D01*
X949356Y-194439D01*
X948483Y-196188D01*
X947828Y-198522D01*
X947610Y-201147D01*
X947828Y-203772D01*
X948483Y-206106D01*
X949356Y-207856D01*
X950666Y-209314D01*
X952413Y-209897D01*
X954159Y-209314D01*
X955470Y-207856D01*
X956343Y-206106D01*
X956998Y-203772D01*
X957216Y-201147D01*
X956998Y-198522D01*
X956343Y-196188D01*
X955470Y-194439D01*
X954159Y-192980D01*
X952413Y-192397D01*
G01X969913Y-209897D02*
X971441Y-209605D01*
X973188Y-208731D01*
X974280Y-207273D01*
X974716Y-205230D01*
X974280Y-203189D01*
X972970Y-201439D01*
X971005Y-200564D01*
X968821D01*
X967511Y-199980D01*
X966419Y-198522D01*
X965983Y-196481D01*
X966638Y-194439D01*
X968166Y-192980D01*
X969913Y-192397D01*
X971659Y-192980D01*
X973188Y-194439D01*
X973843Y-196481D01*
X973406Y-198522D01*
X972315Y-199980D01*
X971005Y-200564D01*
X968821D01*
X966856Y-201439D01*
X965546Y-203189D01*
X965110Y-205230D01*
X965546Y-207273D01*
X966638Y-208731D01*
X968385Y-209605D01*
X969913Y-209897D01*
G01X983483Y-210480D02*
X991343Y-192397D01*
G01X1004913D02*
X1003166Y-192980D01*
X1001856Y-194439D01*
X1000983Y-196188D01*
X1000328Y-198522D01*
X1000110Y-201147D01*
X1000328Y-203772D01*
X1000983Y-206106D01*
X1001856Y-207856D01*
X1003166Y-209314D01*
X1004913Y-209897D01*
X1006659Y-209314D01*
X1007970Y-207856D01*
X1008843Y-206106D01*
X1009498Y-203772D01*
X1009716Y-201147D01*
X1009498Y-198522D01*
X1008843Y-196188D01*
X1007970Y-194439D01*
X1006659Y-192980D01*
X1004913Y-192397D01*
G01X1022413Y-209897D02*
Y-192397D01*
X1019793Y-195897D01*
G01Y-209897D02*
X1025033D01*
G01X1035983Y-210480D02*
X1043843Y-192397D01*
G01X1053265Y-195314D02*
X1054575Y-193564D01*
X1056103Y-192689D01*
X1057850Y-192397D01*
X1060033Y-192980D01*
X1061561Y-194439D01*
X1061998Y-196188D01*
X1061780Y-197939D01*
X1060906Y-199397D01*
X1056540Y-202314D01*
X1054575Y-204355D01*
X1053265Y-207273D01*
X1052828Y-209897D01*
X1061998D01*
G01X1074913Y-192397D02*
X1073166Y-192980D01*
X1071856Y-194439D01*
X1070983Y-196188D01*
X1070328Y-198522D01*
X1070110Y-201147D01*
X1070328Y-203772D01*
X1070983Y-206106D01*
X1071856Y-207856D01*
X1073166Y-209314D01*
X1074913Y-209897D01*
X1076659Y-209314D01*
X1077970Y-207856D01*
X1078843Y-206106D01*
X1079498Y-203772D01*
X1079716Y-201147D01*
X1079498Y-198522D01*
X1078843Y-196188D01*
X1077970Y-194439D01*
X1076659Y-192980D01*
X1074913Y-192397D01*
G01X1092413Y-209897D02*
Y-192397D01*
X1089793Y-195897D01*
G01Y-209897D02*
X1095033D01*
G01X1112533D02*
Y-192397D01*
X1104454Y-204939D01*
X1115372D01*
G01X1000110Y-164897D02*
Y-147397D01*
X1004476D01*
X1006223Y-148272D01*
X1007533Y-149439D01*
X1008625Y-151188D01*
X1009498Y-153231D01*
X1009716Y-156147D01*
X1009498Y-159064D01*
X1008625Y-161106D01*
X1007533Y-162856D01*
X1006223Y-164022D01*
X1004476Y-164897D01*
X1000110D01*
G01X1026343D02*
Y-153231D01*
G01Y-155272D02*
X1025470Y-154106D01*
X1024159Y-153522D01*
X1022631Y-153231D01*
X1021103Y-153814D01*
X1019793Y-154980D01*
X1018919Y-156730D01*
X1018483Y-159064D01*
X1018919Y-161397D01*
X1019793Y-163147D01*
X1021103Y-164314D01*
X1022631Y-164897D01*
X1024159Y-164605D01*
X1025470Y-163731D01*
X1026343Y-162564D01*
G01X1039913Y-147397D02*
Y-164897D01*
G01X1036856Y-153231D02*
X1042970D01*
G01X1054138Y-157022D02*
X1061125D01*
X1060470Y-154980D01*
X1059378Y-153814D01*
X1057850Y-153231D01*
X1056321Y-153522D01*
X1055011Y-154397D01*
X1054138Y-156439D01*
X1053701Y-158189D01*
Y-159939D01*
X1054138Y-161689D01*
X1055230Y-163439D01*
X1056540Y-164605D01*
X1058068Y-164897D01*
X1059596Y-164314D01*
X1061125Y-162564D01*
G54D17*
X986308Y1460976D03*
Y1456976D03*
Y1447976D03*
Y1540976D03*
Y1536976D03*
Y1526976D03*
Y1500976D03*
Y1496976D03*
Y1487976D03*
X999107Y1605976D03*
X986308Y1582976D03*
Y1577976D03*
Y1566976D03*
G54D27*
G01X28900Y417800D02*
X28200D01*
X22771Y423229D01*
X11075D01*
X11069Y423223D01*
G01Y553145D02*
X11075Y553151D01*
X33698D01*
X33799Y553050D01*
G01X42867Y548450D02*
X36567Y542150D01*
X22399D01*
X21589Y541340D01*
X11075D01*
X11069Y541334D01*
G01X33307Y557938D02*
X31858Y559387D01*
X28337D01*
X26038Y557088D01*
X11075D01*
X11069Y557082D01*
G01X42599Y567850D02*
X39099Y564350D01*
X32846D01*
X29521Y561025D01*
X11075D01*
X11069Y561019D01*
G01X26199Y547176D02*
X26023Y547000D01*
X24549D01*
X22335Y549214D01*
X11075D01*
X11069Y549208D01*
G01X49799Y559150D02*
X35926Y545277D01*
X11075D01*
X11069Y545271D01*
G01X27199Y539600D02*
X25002Y537403D01*
X11075D01*
X11069Y537397D01*
G01X31549Y566050D02*
X26441D01*
X26335Y565944D01*
X25966D01*
X23753Y563731D01*
X22245D01*
X22226Y563750D01*
X21350D01*
X20138Y564962D01*
X11075D01*
X11069Y564956D01*
G01X25581Y567763D02*
X24445Y568899D01*
X11075D01*
X11069Y568893D01*
G01X27699Y573750D02*
X26785Y572836D01*
X11075D01*
X11069Y572830D01*
G01Y592515D02*
X11075Y592521D01*
X28179D01*
X28808Y593150D01*
G01X28700Y596549D02*
X28609Y596458D01*
X11075D01*
X11069Y596452D01*
G01X32200Y603710D02*
X30810D01*
X27495Y600395D01*
X11075D01*
X11069Y600389D01*
G01X31598Y607102D02*
X31002D01*
X28232Y604332D01*
X11075D01*
X11069Y604326D01*
G01X27700Y682700D02*
X23391Y687009D01*
X11075D01*
X11069Y687003D01*
G01X44046Y799554D02*
Y794746D01*
X34744Y785444D01*
X11067D01*
X11060Y785451D01*
G01X37416Y799033D02*
X35632Y797249D01*
X11073D01*
X11060Y797262D01*
G01X37099Y811350D02*
X34809Y809060D01*
X11073D01*
X11060Y809073D01*
G01Y805136D02*
X11073Y805123D01*
X42123D01*
X43300Y806300D01*
G01X11060Y801199D02*
X24753D01*
X25100Y800852D01*
X40113D01*
X40711Y801450D01*
X52299D01*
G01X35300Y789375D02*
X11073D01*
X11060Y789388D01*
G01X35559Y795112D02*
X33759Y793312D01*
X11073D01*
X11060Y793325D01*
G01X45100Y793100D02*
X33501Y781501D01*
X11073D01*
X11060Y781514D01*
G01X44899Y836250D02*
X33436D01*
X30236Y839450D01*
X27550D01*
X20783Y832683D01*
X11073D01*
X11060Y832696D01*
G01X46700Y820100D02*
X45251Y818651D01*
X36898D01*
X34678Y820871D01*
X11073D01*
X11060Y820884D01*
G01X54799Y838050D02*
X54480Y838369D01*
X33634D01*
X30915Y841088D01*
X26137D01*
X21669Y836620D01*
X11073D01*
X11060Y836633D01*
G01Y840570D02*
X11073Y840557D01*
X22906D01*
X25075Y842726D01*
X47576D01*
X47592Y842710D01*
X49138D01*
X50399Y841450D01*
G01X55299Y844350D02*
X53301Y846348D01*
X47592D01*
X45751Y844507D01*
X11060D01*
G01Y816947D02*
X11073Y816934D01*
X49766D01*
X53950Y812750D01*
X59800D01*
G01X31699Y814350D02*
X28599D01*
X27246Y812997D01*
X11073D01*
X11060Y813010D01*
G01X23299Y863050D02*
Y858850D01*
X20754Y856305D01*
X11073D01*
X11060Y856318D01*
G01X61600Y850531D02*
X61050Y851081D01*
X19963D01*
X18663Y852381D01*
X11060D01*
G01Y848444D02*
X11073Y848431D01*
X47200D01*
G01X76000Y1431100D02*
X61900Y1417000D01*
X29382D01*
X26500Y1414118D01*
Y1412200D01*
X21781Y1407481D01*
X11075D01*
X11069Y1407475D01*
G01X34896Y1555730D02*
X31230D01*
X28651Y1553151D01*
X11075D01*
X11069Y1553145D01*
G01X46700Y1546793D02*
Y1551122D01*
X45053Y1552769D01*
X34199D01*
X32930Y1551500D01*
X20900D01*
X18608Y1549208D01*
X11069D01*
G01X41325Y1548747D02*
X22847D01*
X19371Y1545271D01*
X11069D01*
G01X91399Y1549550D02*
X64399D01*
X59823Y1544974D01*
X32296D01*
X30953Y1543631D01*
X25231D01*
X22940Y1541340D01*
X11075D01*
X11069Y1541334D01*
G01X38500Y1534600D02*
X36500D01*
X33138Y1531238D01*
X24238D01*
X18592Y1525592D01*
X11075D01*
X11069Y1525586D01*
G01X81999Y1541550D02*
X79404D01*
X77804Y1543150D01*
X62716D01*
X60778Y1541212D01*
X40769D01*
X40731Y1541250D01*
X34650D01*
X33612Y1540212D01*
X27259D01*
X25299Y1538252D01*
X25272D01*
X23248Y1536228D01*
Y1536201D01*
X20513Y1533466D01*
X11075D01*
X11069Y1533460D01*
G01Y1537397D02*
X11075Y1537403D01*
X21852D01*
X26299Y1541850D01*
X32933D01*
X33971Y1542888D01*
X60137D01*
X63899Y1546650D01*
X72599D01*
G01X70099Y1540550D02*
X62433D01*
X61457Y1539574D01*
X35291D01*
X34291Y1538574D01*
X27938D01*
X25978Y1536614D01*
X25951D01*
X24886Y1535549D01*
Y1535522D01*
X18893Y1529529D01*
X11075D01*
X11069Y1529523D01*
G01X24199Y1523700D02*
X22154Y1521655D01*
X11075D01*
X11069Y1521649D01*
G01X36340Y1558809D02*
X30858D01*
X29137Y1557088D01*
X11075D01*
X11069Y1557082D01*
G01Y1576767D02*
X11602Y1577300D01*
X59365D01*
X59822Y1576843D01*
X61578D01*
X62035Y1577300D01*
X76080D01*
X78462Y1574918D01*
G01X11069Y1580704D02*
X11075Y1580710D01*
X20790D01*
X22538Y1578962D01*
X60700D01*
G01X11069Y1584641D02*
X11075Y1584647D01*
X35600D01*
X37173Y1583074D01*
G01X11069Y1588578D02*
X11075Y1588584D01*
X38416D01*
X40200Y1586800D01*
G01X32700Y1673300D02*
X26000D01*
X23961Y1671261D01*
X11075D01*
X11069Y1671255D01*
G01X30274Y1787238D02*
X24200Y1793312D01*
X11073D01*
X11060Y1793325D01*
G01X38878Y1799571D02*
X37263Y1801186D01*
X11073D01*
X11060Y1801199D01*
G01Y1805136D02*
X11073Y1805123D01*
X36300D01*
G01X35675Y1783450D02*
X35673Y1783452D01*
X30499D01*
X24576Y1789375D01*
X11073D01*
X11060Y1789388D01*
G01X39324Y1780623D02*
X30499D01*
X25684Y1785438D01*
X11073D01*
X11060Y1785451D01*
G01X43751Y1780559D02*
X41996Y1778804D01*
X29518D01*
X26821Y1781501D01*
X11073D01*
X11060Y1781514D01*
G01X47440Y1761391D02*
X43078Y1765753D01*
X11073D01*
X11060Y1765766D01*
G01X32099Y1797150D02*
X32000Y1797249D01*
X11073D01*
X11060Y1797262D01*
G01Y1769703D02*
X43165D01*
X43171Y1769709D01*
X44679D01*
X44685Y1769703D01*
X46906D01*
X47604Y1769005D01*
G01X45782Y1771877D02*
X44032Y1773627D01*
X11073D01*
X11060Y1773640D01*
G01X47499Y1775350D02*
X46399Y1776450D01*
X28999D01*
X27885Y1777564D01*
X11073D01*
X11060Y1777577D01*
G01X28550Y1828153D02*
X27957Y1828746D01*
X11073D01*
X11060Y1828759D01*
G01X29899Y1821050D02*
X25784Y1816935D01*
X11073D01*
X11060Y1816948D01*
G01X34099Y1822850D02*
X34080Y1822869D01*
X28518D01*
X26521Y1820872D01*
X11073D01*
X11060Y1820885D01*
G01X26099Y1824950D02*
X25958Y1824809D01*
X11073D01*
X11060Y1824822D01*
G01X25999Y1842550D02*
X24006Y1840557D01*
X11073D01*
X11060Y1840570D01*
G01X43099Y1833850D02*
X38449Y1838500D01*
X21444D01*
X19577Y1836633D01*
X11060D01*
G01X39699Y1833850D02*
X12240D01*
X11073Y1832683D01*
X11060Y1832696D01*
G01X61400Y452600D02*
X61300Y452700D01*
X57300D01*
G01X65000Y455500D02*
X67600D01*
X68800Y454300D01*
G01X39217Y554750D02*
X37517Y553050D01*
X33799D01*
G01X33699Y561850D02*
X34149Y561450D01*
X37849D01*
G01X65599Y514250D02*
Y510401D01*
X80900Y495100D01*
X82403D01*
X82453Y495050D01*
X123999D01*
G01X68000Y546500D02*
X66500Y545000D01*
Y543000D01*
G01X72500Y545000D02*
X73000Y545500D01*
Y548700D01*
G01X36499Y566350D02*
X36199Y566050D01*
X31549D01*
G01X28808Y593150D02*
X32341D01*
X32505Y592986D01*
G01X32300Y597800D02*
X29951D01*
X28700Y596549D01*
G01X35766Y602721D02*
X33189D01*
X32200Y603710D01*
G01X35157Y608117D02*
X35117D01*
X34022Y607022D01*
X31678D01*
X31598Y607102D01*
G01X43300Y806300D02*
X51100D01*
G01X49900Y813200D02*
X53300Y809800D01*
X81300D01*
X88000Y816500D01*
X89000D01*
G01X56281Y801350D02*
X56181Y801450D01*
X52299D01*
G01X49300Y836500D02*
X49050Y836250D01*
X44899D01*
G01X58699Y837250D02*
X57899Y838050D01*
X54799D01*
G01X68860Y838706D02*
X64599D01*
X61855Y841450D01*
X50399D01*
G01X90000Y826000D02*
X81566D01*
X68860Y838706D01*
G01X54000Y819900D02*
Y815824D01*
X54074Y815750D01*
G01X55299Y844350D02*
X56149Y845200D01*
X67249D01*
X69499Y842950D01*
G01X90500Y831500D02*
X78731D01*
X78453Y831686D01*
X69008Y841131D01*
X65418D01*
X63499Y843050D01*
G01X59800Y812750D02*
X62432Y815382D01*
Y820273D01*
X62405Y820300D01*
G01X74220Y854150D02*
X70601Y850531D01*
X61600D01*
G01X72362Y849550D02*
X70812Y848000D01*
X47631D01*
X47200Y848431D01*
G01X72000Y1013400D02*
Y1017700D01*
X72300Y1018000D01*
G01X63273Y1023974D02*
Y1023077D01*
X66000Y1020350D01*
G01X90000Y993100D02*
X88005Y995095D01*
Y996217D01*
G01X92600Y996100D02*
X93500Y997000D01*
Y1000300D01*
G01X66499Y1025050D02*
X70199D01*
G01X79600Y1019100D02*
X75900D01*
G01X77758Y1357742D02*
X25000D01*
G01X29631Y1533063D02*
X32532D01*
X37088Y1537619D01*
X76673D01*
X77842Y1536450D01*
X85000D01*
G01D02*
X100800D01*
G01X41325Y1548747D02*
X42096D01*
X44299Y1550950D01*
G01X96200Y1550100D02*
X95650Y1549550D01*
X91399D01*
G01X99899Y1539850D02*
X98199Y1541550D01*
X81999D01*
G01X100000Y1546650D02*
X72599D01*
G01X90324Y1538800D02*
X79100D01*
X77350Y1540550D01*
X70099D01*
G01X98144Y1534309D02*
X61191D01*
X60000Y1535500D01*
G01D02*
X59891Y1535609D01*
X42082D01*
X39254Y1532781D01*
X36998D01*
X33298Y1529081D01*
X29580D01*
X24199Y1523700D01*
G01X37173Y1583074D02*
X38647Y1581600D01*
X43083D01*
X43359Y1581324D01*
X71738D01*
X72200Y1580862D01*
X78776D01*
X84229Y1575409D01*
Y1567329D01*
X80529Y1563629D01*
Y1557609D01*
X79000Y1556080D01*
Y1555500D01*
G01X40200Y1586800D02*
X44038Y1582962D01*
X72900D01*
X73100Y1582762D01*
X79564D01*
X86129Y1576197D01*
Y1566541D01*
X82429Y1562841D01*
Y1555500D01*
G01X78600Y1561900D02*
Y1566200D01*
X78400Y1566400D01*
G01X75000Y1561800D02*
Y1557900D01*
X74600Y1557500D01*
G01X74800Y1584700D02*
X74000Y1585500D01*
X49000D01*
G01X33599Y1600200D02*
X46799Y1587000D01*
X47500D01*
X49000Y1585500D01*
G01X74700Y1574600D02*
X74500Y1574800D01*
X40300D01*
X39000Y1573500D01*
G01X80400Y1571766D02*
X80379Y1571787D01*
Y1573001D01*
X78462Y1574918D01*
G01X82329Y1568117D02*
Y1574621D01*
X77988Y1578962D01*
X60700D01*
G01X74500Y1692000D02*
Y1694500D01*
X68000Y1701000D01*
G01X21600Y1702900D02*
X23200Y1704500D01*
X64500D01*
X68000Y1701000D01*
G01X85599Y1797350D02*
X82899Y1794650D01*
X49950D01*
X47800Y1796800D01*
X46249D01*
X43478Y1799571D01*
X38878D01*
G01X36300Y1805123D02*
X41426D01*
X47899Y1798650D01*
G01X48049Y1791450D02*
X48099D01*
X49399Y1792750D01*
X98250D01*
X112500Y1778500D01*
Y1737551D01*
X109499Y1734550D01*
Y1712213D01*
G01X46199Y1783050D02*
X48299D01*
X55299Y1776050D01*
X62399D01*
G01X74400Y1778100D02*
X72350Y1776050D01*
X62399D01*
G01X99199Y1761899D02*
X71448Y1789650D01*
X62300D01*
G01D02*
X62281Y1789631D01*
X41993D01*
X37574Y1794050D01*
G01X99999Y1753575D02*
Y1756801D01*
X69250Y1787550D01*
X63197D01*
X63178Y1787531D01*
X61422D01*
X61153Y1787800D01*
X38453D01*
X38222Y1788031D01*
X36945D01*
X36926Y1788050D01*
X34032D01*
X31811Y1790271D01*
G01X40478Y1795820D02*
X39148Y1797150D01*
X32099D01*
G01X110099Y1759875D02*
Y1758785D01*
X101432Y1750118D01*
X96214D01*
X78182Y1768150D01*
X48459D01*
X47604Y1769005D01*
G01X101399Y1784700D02*
X101818Y1784281D01*
Y1752821D01*
X100753Y1751756D01*
X96893D01*
X75099Y1773550D01*
X68999D01*
G01D02*
X49299D01*
X47499Y1775350D01*
G01X29599Y1844350D02*
X35172D01*
X44918Y1834604D01*
Y1833096D01*
X43172Y1831350D01*
X33199D01*
X30002Y1828153D01*
X28550D01*
G01X96600Y1826000D02*
X76766D01*
X76288Y1826478D01*
X43023D01*
X37576Y1821031D01*
X29918D01*
X29899Y1821050D01*
G01X91499Y1805549D02*
X98151D01*
X135300Y1768400D01*
Y1725269D01*
X135899Y1724670D01*
Y1722550D01*
G01X35876Y1812350D02*
X41177Y1807049D01*
X89999D01*
X91499Y1805549D01*
G01X34129Y1815267D02*
X43702Y1824840D01*
X75609D01*
X83349Y1817100D01*
X86649D01*
G01X61009Y1822340D02*
X70777D01*
X82567Y1810550D01*
X115729D01*
X121151Y1805128D01*
G01X40299Y1828750D02*
X36399D01*
G01D02*
X32599Y1824950D01*
X26099D01*
G01X46499Y1836550D02*
X46999Y1836050D01*
X50199D01*
Y1836052D01*
G01X47166Y1839884D02*
Y1840217D01*
X49616Y1842667D01*
G01X141499Y427550D02*
X142999D01*
X144999Y425550D01*
G01X176799Y493850D02*
X175599Y495050D01*
X123999D01*
G01X150750Y540416D02*
X112184D01*
X109400Y543200D01*
G01X149000Y537500D02*
X111700D01*
X106000Y543200D01*
G01X105600Y1069500D02*
X112500Y1062600D01*
Y1059173D01*
X112699Y1058974D01*
G01X109499Y1080550D02*
X105499D01*
G01X164700Y1085400D02*
X163413Y1086687D01*
X116187D01*
X110050Y1080550D01*
X109499D01*
G01X106718Y1076050D02*
X108109Y1074659D01*
X111140D01*
G01X123999Y1102550D02*
X123599Y1102350D01*
X120982Y1099733D01*
G01X108999Y1102050D02*
X109499Y1101550D01*
Y1098350D01*
G01X131999Y1710050D02*
X131599Y1710450D01*
Y1714150D01*
G01X112753Y1716613D02*
X112890Y1716750D01*
X116499D01*
G01X135499Y1710150D02*
X135899Y1710550D01*
Y1722550D01*
G01X123749Y1711550D02*
X127049Y1708250D01*
X127499D01*
G01X103920Y1833104D02*
X144700Y1792324D01*
Y1748748D01*
X142380Y1746428D01*
Y1717193D01*
X143319Y1716254D01*
Y1714746D01*
X136804Y1708231D01*
X127518D01*
X127499Y1708250D01*
G01X141999Y1764550D02*
Y1784280D01*
X121151Y1805128D01*
G01X97999Y1843050D02*
Y1839025D01*
X103920Y1833104D01*
G01X253871Y291410D02*
Y302422D01*
X280345Y328896D01*
G01X188000Y484500D02*
X187900Y484400D01*
X184200D01*
G01X254499Y697700D02*
Y708050D01*
X284764Y738315D01*
G01X211750Y894600D02*
X212740Y893610D01*
X215500D01*
G01X200799Y896600D02*
X200809Y896610D01*
X204699D01*
G01X199500Y1627000D02*
X197499D01*
X179999Y1644500D01*
G01X247252Y1826803D02*
X201499Y1781050D01*
G01X285499Y1930050D02*
X288361Y1927188D01*
Y1867912D01*
X247252Y1826803D01*
G01X341499Y67110D02*
X337799D01*
G01X326499Y334054D02*
X326003D01*
X323499Y331550D01*
G01X284999Y338650D02*
Y342750D01*
G01X301249Y346050D02*
X297499D01*
X280345Y328896D01*
G01X327999Y740550D02*
X329519D01*
X331263Y742294D01*
G01X285499Y745050D02*
Y748815D01*
X285264Y749050D01*
G01X306500Y753550D02*
X297999D01*
X284764Y740315D01*
Y738315D01*
G01X283499Y1556050D02*
X285299D01*
X286831Y1557582D01*
X286868D01*
G01X310249Y1569800D02*
X310499Y1569550D01*
Y1566550D01*
X290411Y1546462D01*
G01D02*
Y1530787D01*
X274824Y1515200D01*
X262849D01*
X261999Y1516050D01*
G01X348499Y1762050D02*
X299995Y1810554D01*
G01X288709Y1948042D02*
X289999Y1946752D01*
Y1820550D01*
X299995Y1810554D01*
G01X331622Y1944767D02*
X331499Y1944450D01*
Y1940750D01*
G01X381999Y57050D02*
X382999D01*
X385499Y59550D01*
G01X381999Y53550D02*
Y53350D01*
X379768Y51119D01*
X378428D01*
G01X394199Y45050D02*
Y65850D01*
X390411Y69638D01*
G01X371700Y85500D02*
X374549D01*
X390411Y69638D01*
G01X353499Y1710450D02*
Y1710550D01*
X363499Y1720550D01*
X526499D01*
X740999Y1935050D01*
X755999D01*
G01X385499Y1735050D02*
X525474D01*
X732974Y1942550D01*
X756499D01*
G01X793000Y1803500D02*
X760200D01*
X741591Y1822109D01*
X711652D01*
G01X711848Y1825504D02*
X740884D01*
X760888Y1805500D01*
X795849D01*
G01X771499Y1936550D02*
X769999Y1935050D01*
X755999D01*
G01X794499Y1941050D02*
X792999Y1942550D01*
X756499D01*
G01X791499Y333050D02*
X795199D01*
G01X789999Y336550D02*
Y340250D01*
G01X772499Y323050D02*
X776199D01*
G01X772873Y326924D02*
Y330624D01*
G01X771105Y722789D02*
X770999Y723050D01*
Y726750D01*
G01X788999Y736050D02*
X787095Y737954D01*
X785826D01*
G01X791999Y733050D02*
Y729350D01*
G01X769999Y733050D02*
X774199D01*
G01X792154Y1135926D02*
X795854D01*
G01X771999Y1124550D02*
X771770Y1124321D01*
X768306D01*
G01X772499Y1130050D02*
X774383Y1131934D01*
Y1133235D01*
G01X789499Y1138050D02*
X788854Y1138926D01*
Y1142626D01*
G01X779499Y1131050D02*
X781403Y1129146D01*
X782672D01*
G01X774542Y1530050D02*
Y1526350D01*
G01X774577Y1533796D02*
X774499Y1534850D01*
Y1537484D01*
X774488Y1537495D01*
G01X791499Y1543550D02*
X787799D01*
G01X797699Y1541050D02*
X793999D01*
G01X784499Y1529050D02*
X789500Y1524049D01*
Y1492049D01*
X798149Y1483400D01*
X870649D01*
X883249Y1470800D01*
Y1455300D01*
X861849Y1433900D01*
Y1383500D01*
G01X807000Y1822300D02*
X802399Y1817699D01*
Y1809362D01*
X796537Y1803500D01*
X793000D01*
G01X795849Y1805500D02*
X800499Y1810150D01*
Y1819707D01*
X803500Y1822708D01*
G01X782999Y1937050D02*
Y1915501D01*
X815450Y1883050D01*
X833999D01*
G01X917499Y1796550D02*
Y1818901D01*
X866375Y1870025D01*
X865524D01*
X852499Y1883050D01*
X833999D01*
G01X771499Y1940050D02*
X775199D01*
G01X792499Y1949050D02*
Y1950705D01*
X790844Y1952360D01*
G01X861849Y1383500D02*
Y1376050D01*
G01X986400Y1639302D02*
Y1639400D01*
X988102Y1641102D01*
X1004307D01*
G01X969600Y1638300D02*
X971798Y1636102D01*
X1004307D01*
G01X977500Y1660500D02*
X978900Y1661900D01*
X982200D01*
X982998Y1661102D01*
X1004307D01*
G01X978000Y1668000D02*
Y1668100D01*
X981002Y1671102D01*
X1004307D01*
G01X967600Y1651100D02*
X967602Y1651102D01*
X981277D01*
X981296Y1651121D01*
X982804D01*
X982823Y1651102D01*
X1004307D01*
G01Y1646102D02*
X993098D01*
X991381Y1647819D01*
X988748D01*
X987429Y1646500D01*
X971558D01*
G54D18*
X997608Y1492322D03*
Y1452322D03*
Y1572322D03*
Y1532322D03*
G54D28*
G01X11069Y391726D02*
X19494D01*
X19500Y391732D01*
G03X19889Y391893I0J550D01*
G01X20766Y392770D01*
G02X21399Y393032I633J-633D01*
G01X29209D01*
G02X32229Y391781I0J-4272D01*
G01X66081Y357929D01*
G02X67399Y354747I-3182J-3182D01*
G01Y292613D01*
G03X69098Y288512I5800J0D01*
G01X124011Y233599D01*
G03X128112Y231900I4101J4101D01*
G01X819160D01*
G03X824329Y234041I0J7310D01*
G01X840096Y249808D01*
G02X841864Y250540I1768J-1768D01*
G01X846671D01*
G02X847878Y250040I0J-1707D01*
G01X11069Y395663D02*
X19664D01*
X19670Y395669D01*
G02X20539Y395309I0J-1229D01*
G01X21199Y394650D01*
G03X21967Y394332I768J768D01*
G01X29209D01*
G02X33149Y392700I0J-5572D01*
G01X67000Y358849D01*
G02X68699Y354748I-4101J-4101D01*
G01Y292614D01*
G03X70017Y289432I4500J0D01*
G01X124931Y234518D01*
G03X128113Y233200I3182J3182D01*
G01X819160D01*
G03X823409Y234960I0J6010D01*
G01X839176Y250727D01*
G02X841863Y251840I2687J-2687D01*
G01X848580D01*
G02X850000Y251252I0J-2008D01*
G01X851278Y249974D01*
G01X115876Y125973D02*
G03X114234Y127250I-1642J-417D01*
G01X105815D01*
G03X104362Y126996I1J-4290D01*
G03X102783Y125995I1452J-4037D01*
G01X99352Y122564D01*
G02X94969Y120750I-4381J4383D01*
G01X86671D01*
G02X82285Y122436I0J6548D01*
G02X82036Y122673I4506J4984D01*
G01X62703Y142006D01*
X62330Y142380D01*
X62006Y142703D01*
X61078Y143630D01*
G02X59999Y146239I2609J2606D01*
G01Y346252D01*
G03X59673Y347562I-2796J0D01*
G03X59179Y348230I-2470J-1310D01*
G01X38242Y369167D01*
G03X37272Y369490I-798J-778D01*
G02X36301Y369814I-172J1102D01*
G01X35506Y370609D01*
G02X35182Y371580I778J799D01*
G03X34859Y372550I-1102J172D01*
G01X31304Y376105D01*
X31294Y376114D01*
X31276Y376132D01*
G03X28498Y377284I-2779J-2776D01*
G01X23000D01*
G03X20991Y376510I0J-2994D01*
G02X19671Y375999I-1319J1448D01*
G01X11069Y375978D01*
G01X115876Y130050D02*
G02X115576Y129328I-1021J1D01*
G01X115204Y128956D01*
G02X114754Y128656I-980J983D01*
G01X114622Y128601D01*
G02X114366Y128550I-256J617D01*
G01X105814D01*
G03X101864Y126915I1J-5590D01*
G01X98432Y123484D01*
G02X94970Y122050I-3462J3462D01*
G01X86672D01*
G02X83157Y123402I1J5247D01*
G02X82956Y123593I3630J4022D01*
G01X63249Y143300D01*
X62925Y143623D01*
X61998Y144550D01*
G02X61299Y146238I1688J1688D01*
G01Y346253D01*
G03X60099Y349150I-4097J0D01*
G01X32222Y377027D01*
X32196Y377052D01*
G03X28499Y378584I-3698J-3697D01*
G01X22385D01*
G02X21346Y378865I-1J2059D01*
G02X20929Y379187I1040J1777D01*
G03X19157Y379921I-1772J-1772D01*
G01X19151Y379915D01*
X11069D01*
G01Y435035D02*
X19410D01*
X19416Y435041D01*
G02X20811Y434463I0J-1973D01*
G01X21061Y434213D01*
G03X22290Y433704I1229J1229D01*
G01X67499D01*
G02X71228Y432160I1J-5273D01*
G01X71368Y432019D01*
X73918Y429469D01*
X73944Y429442D01*
G03X76099Y428550I2154J2155D01*
G01X81625D01*
G03X83393Y429282I0J2500D01*
G01X86634Y432523D01*
G02X89321Y433636I2687J-2687D01*
G01X276099D01*
G03X280120Y434048I1J19820D01*
G03X282747Y434823I-3365J16247D01*
G01X798618Y642139D01*
X802985Y643920D01*
X802992Y643923D01*
X802993D01*
X836319Y657326D01*
G02X837737Y657600I1417J-3526D01*
G01X847629D01*
G02X849976Y656628I0J-3319D01*
G01X851172Y655432D01*
G01X11069Y431098D02*
X19787D01*
X19793Y431104D01*
G03X20607Y431441I0J1151D01*
G01X21157Y431991D01*
G02X22154Y432404I997J-997D01*
G01X67583D01*
G02X70248Y431300I0J-3769D01*
G01X72698Y428850D01*
X73024Y428523D01*
G03X76099Y427250I3074J3075D01*
G01X81626D01*
G03X84313Y428363I0J3800D01*
G01X87554Y431604D01*
G02X89322Y432336I1768J-1768D01*
G01X276099D01*
G03X280296Y432766I-1J20709D01*
G03X280387Y432785I-4050J19624D01*
G03X283100Y433563I-4105J19433D01*
G01X800299Y641413D01*
X803476Y642716D01*
X803477D01*
X836805Y656117D01*
X836809Y656119D01*
G02X837742Y656300I934J-2319D01*
G01X846842D01*
G02X847772Y655370I0J-930D01*
G01X26299Y478404D02*
X26014Y478689D01*
G03X23699Y479648I-2315J-2315D01*
G01X21614D01*
G03X20503Y479188I0J-1571D01*
G01X19991Y478675D01*
G02X19200Y478348I-790J791D01*
G01X19194Y478342D01*
X11069D01*
G01Y450783D02*
X19727D01*
X19733Y450789D01*
G02X20585Y450436I0J-1205D01*
G01X21135Y449886D01*
G03X22069Y449499I934J934D01*
G01X35935D01*
G03X39117Y450817I0J4500D01*
G01X48801Y460501D01*
G02X52902Y462200I4101J-4101D01*
G01X176044D01*
G03X179226Y463518I0J4500D01*
G01X181653Y465945D01*
X181654D01*
X777376Y1061667D01*
G02X781299Y1063292I3923J-3923D01*
G01X847999D01*
G02X849677Y1062597I0J-2373D01*
G01X850833Y1061441D01*
G01X11069Y446846D02*
X11075Y446852D01*
X19827D01*
G03X20583Y447165I0J1069D01*
G01X21083Y447665D01*
G02X21424Y447933I1289J-1289D01*
G02X22372Y448199I948J-1557D01*
G01X35936D01*
G03X40037Y449898I0J5800D01*
G01X49721Y459582D01*
G02X52903Y460900I3182J-3182D01*
G01X176046D01*
G03X180147Y462599I0J5800D01*
G01X182574Y465026D01*
X778296Y1060747D01*
G02X781299Y1061992I3004J-3002D01*
G01X846026D01*
G02X846291Y1061971I-2J-1707D01*
G02X846962Y1061711I-267J-1685D01*
G02X847233Y1061492I-931J-1430D01*
G01X26486Y462648D02*
G03X24342Y463536I-2144J-2144D01*
G01X21287D01*
G03X20172Y463074I0J-1577D01*
G01X19908Y462811D01*
G02X19400Y462600I-509J508D01*
G01X19394Y462594D01*
X11069D01*
G01X26499Y466250D02*
Y465828D01*
G02X26130Y465093I-916J0D01*
G02X25510Y464836I-620J620D01*
G01X22000D01*
G02X21085Y465215I0J1294D01*
G01X20500Y465800D01*
G03X18735Y466531I-1765J-1765D01*
G01X11069D01*
G01X122397Y252688D02*
Y252036D01*
G03X122598Y251551I686J0D01*
G03X123083Y251350I485J485D01*
G01X125499D01*
G03X126499Y252350I0J1000D01*
G01Y255505D01*
G03X126114Y256433I-1313J-1D01*
G01X125998Y256550D01*
X75912Y306636D01*
G02X74799Y309323I2687J2687D01*
G01Y367875D01*
G03X74067Y369643I-2500J0D01*
G01X35329Y408381D01*
G03X34173Y408860I-1156J-1156D01*
G01X22318D01*
G03X21449Y408500I0J-1229D01*
G01X20849Y407900D01*
G02X19835Y407480I-1014J1014D01*
G01X19829Y407474D01*
X11069D01*
G01X122799Y249150D02*
X123204Y249555D01*
G02X124399Y250050I1195J-1195D01*
G01X125499D01*
G03X127799Y252350I0J2300D01*
G01Y255483D01*
G03X127018Y257367I-2665J-1D01*
G01X127019Y257368D01*
X118194Y266194D01*
X76831Y307557D01*
G02X76099Y309325I1768J1768D01*
G01Y367876D01*
G03X74986Y370563I-3800J0D01*
G01X36248Y409301D01*
G03X34174Y410160I-2074J-2074D01*
G01X22699D01*
G02X21504Y410655I0J1690D01*
G01X21304Y410855D01*
G03X19947Y411417I-1357J-1357D01*
G01X11075D01*
X11069Y411411D01*
G01X853499Y1871036D02*
X852536Y1871999D01*
G03X849999Y1873050I-2537J-2537D01*
G01X846259D01*
G03X844236Y1871893I1J-2348D01*
G01X843997Y1871486D01*
X843620Y1870848D01*
X817275Y1826081D01*
X192400Y764246D01*
X28031Y522175D01*
G03X27754Y521832I1484J-1482D01*
G01X27740Y521811D01*
G03X27199Y519980I2825J-1830D01*
G01Y515937D01*
G02X26441Y514107I-2588J0D01*
G01X25329Y512995D01*
G02X24922Y512686I-1330J1330D01*
G02X24135Y512360I-787J787D01*
G01X21616D01*
G02X20906Y512654I0J1004D01*
G01X20330Y513230D01*
G03X19000Y513781I-1330J-1330D01*
G01X18994Y513775D01*
X11069D01*
G01X850099Y1871056D02*
G03X849603Y1871721I-694J0D01*
G03X849405Y1871750I-199J-665D01*
G01X846260D01*
G03X845357Y1871233I0J-1048D01*
G01X844804Y1870294D01*
X818397Y1825421D01*
X193499Y763550D01*
X29104Y521441D01*
G03X28499Y519980I1460J-1460D01*
G01Y515938D01*
G02X27360Y513188I-3888J-1D01*
G01Y513187D01*
X26861Y512688D01*
X26602Y512430D01*
G02X26058Y511968I-3104J3103D01*
G02X23866Y511060I-2192J2192D01*
G01X22170D01*
G03X21453Y510763I0J-1014D01*
G01X21222Y510531D01*
X20942Y510251D01*
G02X19959Y509844I-983J983D01*
G01X11075D01*
X11069Y509838D01*
G01X848888Y1466402D02*
X848686Y1466605D01*
G03X846751Y1467014I-1282J-1282D01*
G03X846135Y1466613I639J-1656D01*
G01X835635Y1456113D01*
X835640Y1456108D01*
X75106Y528722D01*
X75021Y528627D01*
X44714Y498320D01*
G02X36997Y495396I-7810J8967D01*
G01X22573D01*
G03X20861Y494687I0J-2421D01*
G01X20711Y494537D01*
G02X19646Y494096I-1065J1065D01*
G01X19640Y494090D01*
X11069D01*
G01X852288Y1466346D02*
X851521Y1467113D01*
G03X846284Y1468224I-3473J-3473D01*
G03X845209Y1467526I1112J-2890D01*
G01X834716Y1457033D01*
X74101Y529547D01*
X74082Y529529D01*
X74076Y529521D01*
X43827Y499272D01*
G02X36991Y496696I-6923J8015D01*
G01X22788D01*
G02X20707Y497558I0J2943D01*
G03X19560Y498033I-1147J-1147D01*
G01X19554Y498027D01*
X11069D01*
G01X26515Y481798D02*
Y480944D01*
G02X25744Y480467I-533J0D01*
G03X23699Y480948I-2042J-4094D01*
G01X21657D01*
G02X20486Y481433I0J1656D01*
G01X19800Y482120D01*
G03X19400Y482285I-399J-400D01*
G01X19394Y482279D01*
X11069D01*
G01X26599Y525648D02*
X26031Y526216D01*
G03X24399Y526892I-1632J-1632D01*
G01X22699D01*
G03X20771Y526094I-1J-2726D01*
G02X19559Y525592I-1212J1212D01*
G01X19553Y525586D01*
X11069D01*
G01X26599Y529302D02*
X25765Y528468D01*
G02X25099Y528192I-666J666D01*
G01X21999D01*
G02X20648Y528751I-1J1910D01*
G01X20275Y529125D01*
G03X19300Y529529I-975J-975D01*
G01X19294Y529523D01*
X11069D01*
G01X123393Y1870859D02*
G02X124734Y1872200I1341J0D01*
G01X139605D01*
G02X143863Y1870436I0J-6020D01*
G01X144248Y1870051D01*
Y1870049D01*
X145478Y1868819D01*
G02X147601Y1863700I-5118J-5122D01*
G01X147600D01*
Y1811090D01*
G03X149007Y1807693I4803J-1D01*
G01X149006Y1807692D01*
X151584Y1805115D01*
X151941Y1804759D01*
G02X153250Y1801600I-3160J-3160D01*
G01X153249D01*
Y1785118D01*
G02X152792Y1784203I-1115J-15D01*
G03X152334Y1783288I657J-901D01*
G01Y1782163D01*
G03X152792Y1781248I1115J-14D01*
G02X153249Y1780333I-658J-900D01*
G01Y1779208D01*
G02X152792Y1778293I-1115J-15D01*
G03X152334Y1777378I657J-901D01*
G01Y1776253D01*
G03X152792Y1775338I1115J-14D01*
G02X153249Y1774423I-658J-900D01*
G01Y1773298D01*
G02X152792Y1772383I-1115J-15D01*
G03X152334Y1771468I657J-901D01*
G01Y1770343D01*
G03X152792Y1769428I1115J-14D01*
G02X153249Y1768513I-658J-900D01*
G01Y1767388D01*
G02X152792Y1766473I-1115J-15D01*
G03X152334Y1765558I657J-901D01*
G01Y1764433D01*
G03X152792Y1763518I1115J-14D01*
G02X153249Y1762603I-658J-900D01*
G01Y1761478D01*
G02X152792Y1760563I-1115J-15D01*
G03X152334Y1759648I657J-901D01*
G01Y1758523D01*
G03X152792Y1757608I1115J-14D01*
G02X153249Y1756693I-658J-900D01*
G01Y1693288D01*
G02X149796Y1684952I-11789J0D01*
G01X118397Y1653553D01*
G03X115899Y1647522I6030J-6030D01*
G01Y1471176D01*
G03X118249Y1465502I8026J1D01*
G01X130100Y1453651D01*
G02X132449Y1447980I-5671J-5671D01*
G01Y1411966D01*
G03X135046Y1405696I8866J-1D01*
G01X163046Y1377696D01*
G02X163798Y1375878I-1820J-1817D01*
G01X163799D01*
Y1201694D01*
G03X165305Y1198058I5144J1D01*
G01X186306Y1177057D01*
G02X187398Y1174418I-2641J-2638D01*
G01X187399D01*
Y814859D01*
G02X185434Y810115I-6709J0D01*
G01X145334Y770015D01*
G03X143684Y766031I3983J-3983D01*
G01Y744609D01*
G02X141679Y739769I-6845J0D01*
G01X71980Y670070D01*
G03X70699Y666977I3092J-3092D01*
G01Y634499D01*
X70698Y634500D01*
G02X66872Y625262I-13065J0D01*
G01X61079Y619469D01*
X61078D01*
X60803Y619194D01*
G02X50213Y614806I-10592J10590D01*
G01X21508D01*
G02X20484Y615230I0J1448D01*
G03X18280Y616143I-2204J-2204D01*
G01X18274Y616137D01*
X11069D01*
G01X123592Y1874254D02*
G03X125412Y1873500I1820J1820D01*
G01X139606D01*
G02X144782Y1871356I0J-7320D01*
G01X146250Y1869888D01*
X146398Y1869739D01*
G02X148900Y1863700I-6039J-6040D01*
G01Y1811089D01*
G03X149926Y1808612I3503J0D01*
G01X152503Y1806035D01*
X152860Y1805679D01*
G02X154549Y1801600I-4079J-4078D01*
G01Y1693287D01*
G02X150716Y1684033I-13089J1D01*
G01X119316Y1652633D01*
G03X117199Y1647522I5111J-5111D01*
G01Y1471177D01*
G03X119169Y1466421I6726J0D01*
G01X131019Y1454571D01*
G02X133749Y1447980I-6590J-6591D01*
G01Y1411966D01*
G03X135965Y1406616I7566J0D01*
G01X163965Y1378616D01*
G02X165099Y1375878I-2738J-2738D01*
G01Y1201695D01*
G03X166225Y1198977I3844J0D01*
G01X187225Y1177977D01*
G02X188699Y1174418I-3559J-3559D01*
G01Y814859D01*
G02X186353Y809195I-8009J-1D01*
G01X146253Y769095D01*
G03X144984Y766031I3064J-3064D01*
G01Y744608D01*
G02X142599Y738850I-8145J1D01*
G01X72899Y669150D01*
G03X71999Y666977I2173J-2173D01*
G01Y634500D01*
G02X67792Y624342I-14365J-1D01*
G01X61723Y618274D01*
G02X50212Y613506I-11511J11511D01*
G01X21440D01*
G03X20537Y613132I0J-1277D01*
G02X18301Y612206I-2236J2236D01*
G01X18295Y612200D01*
X11069D01*
G01X124290Y1469241D02*
G03X126279Y1468417I1989J1989D01*
G01X139499D01*
G02X143994Y1466555I0J-6357D01*
G01X173699Y1436850D01*
G02X175172Y1433294I-3556J-3556D01*
G01Y1390468D01*
G02X173886Y1387363I-4393J1D01*
G01X173386Y1386863D01*
G03X172499Y1384722I2141J-2141D01*
G01Y1205589D01*
G03X174209Y1201461I5838J0D01*
G01X194659Y1181011D01*
G02X196099Y1177535I-3476J-3476D01*
G01Y811743D01*
G02X193787Y806161I-7893J-1D01*
G01X153637Y766011D01*
G03X152551Y763390I2622J-2622D01*
G01Y718540D01*
G02X147999Y707550I-15542J0D01*
G01X87999Y647550D01*
G03X85499Y641514I6036J-6036D01*
G01Y639550D01*
G02X83492Y634704I-6854J0D01*
G01X32168Y583380D01*
G02X28861Y582010I-3307J3307D01*
G01X21493D01*
G03X20472Y581587I0J-1444D01*
G02X18355Y580710I-2117J2117D01*
G01X18349Y580704D01*
X11069D01*
G01Y584641D02*
X18459D01*
X18465Y584647D01*
G02X20474Y583815I0J-2841D01*
G03X21693Y583310I1219J1219D01*
G01X28860D01*
G03X31249Y584300I0J3377D01*
G01X36998Y590049D01*
Y590050D01*
X82572Y635624D01*
G03X84199Y639551I-3926J3927D01*
G01Y641514D01*
G02X87080Y648470I9836J1D01*
G01X87079D01*
X147079Y708470D01*
G03X151250Y718540I-10070J10070D01*
G01X151251Y718539D01*
Y763389D01*
G02X152718Y766931I5008J1D01*
G01X192868Y807081D01*
G03X194799Y811743I-4662J4662D01*
G01Y1177534D01*
G03X193739Y1180092I-3616J0D01*
G01X173289Y1200542D01*
G02X171199Y1205588I5048J5047D01*
G01Y1384723D01*
G02X172466Y1387782I4328J-1D01*
G01X172966Y1388282D01*
G03X173872Y1390469I-2187J2187D01*
G01Y1421205D01*
G03X173414Y1422120I-1115J14D01*
G02X172957Y1423035I658J900D01*
G01Y1424160D01*
G02X173414Y1425075I1115J15D01*
G03X173872Y1425990I-657J901D01*
G01Y1433250D01*
G03X172748Y1435961I-3834J-1D01*
G01X143074Y1465635D01*
G03X139498Y1467117I-3576J-3574D01*
G01X124999D01*
G03X123808Y1465926I0J-1191D01*
G01Y1465050D01*
G01X109499Y1743550D02*
X109154Y1743205D01*
G02X105973Y1741850I-3272J3270D01*
G02X105883I-45J4626D01*
G03X102221Y1740524I1J-5722D01*
G03X100949Y1737453I3071J-3071D01*
G01Y1695878D01*
G03X102641Y1691793I5779J1D01*
G01X107541Y1686893D01*
G02X108499Y1684580I-2313J-2313D01*
G01Y1467777D01*
G03X110615Y1462668I7227J1D01*
G01X123716Y1449567D01*
G02X125049Y1446349I-3219J-3218D01*
G01Y1408154D01*
G03X127120Y1403154I7073J1D01*
G01X155861Y1374413D01*
G02X156399Y1373115I-1296J-1298D01*
G01Y1199073D01*
G03X158221Y1194674I6223J1D01*
G01X178772Y1174123D01*
G02X179698Y1171885I-2240J-2237D01*
G01X179699Y1171886D01*
Y816968D01*
G02X178200Y813349I-5118J0D01*
G01X137249Y772398D01*
G03X135714Y768692I3708J-3707D01*
G01Y746900D01*
G02X134582Y744167I-3865J0D01*
G01X134581D01*
X64481Y674067D01*
X64482Y674066D01*
G03X62199Y668554I5511J-5511D01*
G01Y636879D01*
G02X60579Y632970I-5527J1D01*
G02X54748Y630554I-5831J5829D01*
G01X22867D01*
G02X20596Y631494I-1J3211D01*
G03X19638Y631891I-958J-958D01*
G01X19632Y631885D01*
X11069D01*
G01X109399Y1739550D02*
Y1739701D01*
G03X107782Y1740861I-1225J0D01*
G02X105999Y1740550I-1898J5614D01*
G01X105599D01*
G03X102924Y1739442I0J-3783D01*
G03X102249Y1737812I1630J-1630D01*
G01Y1695879D01*
G03X103561Y1692712I4479J0D01*
G01X108460Y1687813D01*
G02X109799Y1684580I-3232J-3232D01*
G01Y1467778D01*
G03X111535Y1463587I5927J0D01*
G01X124635Y1450487D01*
G02X126349Y1446349I-4138J-4138D01*
G01Y1408155D01*
G03X128040Y1404073I5773J0D01*
G01X156781Y1375332D01*
G02X157699Y1373116I-2216J-2216D01*
G01Y1199074D01*
G03X159141Y1195593I4923J0D01*
G01X179691Y1175043D01*
G02X180999Y1171885I-3158J-3158D01*
G01Y816968D01*
G02X179119Y812429I-6418J-1D01*
G01X138169Y771479D01*
G03X137014Y768691I2788J-2788D01*
G01Y746901D01*
G02X135501Y743248I-5165J-1D01*
G01Y743247D01*
X65401Y673147D01*
G03X63499Y668555I4592J-4592D01*
G01Y636878D01*
G02X61499Y632050I-6828J0D01*
G02X54749Y629254I-6750J6750D01*
G01X22828D01*
G03X20737Y628388I0J-2957D01*
G02X19689Y627954I-1048J1048D01*
G01X19683Y627948D01*
X11069D01*
G01X109228Y1333315D02*
X108838Y1333706D01*
G03X106799Y1334550I-2038J-2039D01*
G01X103489D01*
G03X101799Y1333850I0J-2390D01*
G01X99549Y1331600D01*
G03X98779Y1329741I1859J-1859D01*
G01Y1061770D01*
G03X101049Y1056290I7750J0D01*
G01X101050Y1056291D01*
X101969Y1055371D01*
X101968Y1055370D01*
X116420Y1040920D01*
X118839Y1038501D01*
G02X121199Y1032799I-5703J-5700D01*
G01Y749124D01*
G02X118248Y741999I-10075J-1D01*
G01X58649Y682400D01*
G03X55499Y674795I7605J-7605D01*
G01Y648582D01*
G02X54450Y646050I-3580J0D01*
G02X51920Y645002I-2530J2530D01*
G01X21617D01*
G03X20651Y644602I0J-1366D01*
G02X18478Y643702I-2173J2173D01*
G01X18472Y643696D01*
X11069D01*
G01X109228Y1337090D02*
X108828Y1336691D01*
G02X106799Y1335850I-2030J2029D01*
G01X103772D01*
G03X100679Y1334569I0J-4374D01*
G01X98630Y1332520D01*
G03X97479Y1329741I2778J-2778D01*
G01Y1061769D01*
G03X100130Y1055371I9050J2D01*
G01X100129Y1055370D01*
X117919Y1037581D01*
G02X119899Y1032800I-4782J-4781D01*
G01Y749124D01*
G02X117329Y742919I-8775J0D01*
G01X57729Y683319D01*
X57730D01*
G03X54199Y674794I8524J-8524D01*
G01Y648583D01*
G02X53531Y646970I-2281J0D01*
G02X51918Y646302I-1613J1613D01*
G01X22867D01*
G02X21121Y646834I1J3134D01*
G03X20640Y647216I-1899J-1897D01*
G03X19619Y647639I-1021J-1021D01*
G01X19613Y647633D01*
X11069D01*
G01X108845Y931657D02*
X108149Y930960D01*
G02X107399Y930650I-749J750D01*
G01X106983D01*
G03X105579Y930070I-2J-1984D01*
G03X104849Y928305I1766J-1764D01*
G01Y751790D01*
X104848Y751789D01*
Y746436D01*
G02X102941Y741832I-6511J0D01*
G01X48329Y687220D01*
X48330Y687219D01*
G03X44699Y678455I8765J-8766D01*
G01Y666550D01*
G02X40199Y662050I-4500J0D01*
G01X22577D01*
G02X21701Y662412I-1J1238D01*
G01X21339Y662775D01*
G03X19862Y663387I-1477J-1477D01*
G01X11075D01*
X11069Y663381D01*
G01Y659444D02*
X19162D01*
X19168Y659450D01*
G03X21099Y660250I0J2731D01*
G02X22306Y660750I1207J-1207D01*
G01X40199D01*
G03X45999Y666550I0J5800D01*
G01Y678454D01*
G02X49249Y686300I11096J0D01*
G01X103861Y740912D01*
X103860Y740913D01*
G03X106148Y746437I-5523J5523D01*
G01Y751250D01*
X106149Y751251D01*
Y914205D01*
G02X106606Y915120I1115J15D01*
G03X107064Y916035I-657J901D01*
G01Y917160D01*
G03X106606Y918075I-1115J14D01*
G02X106149Y918990I658J900D01*
G01Y928305D01*
G02X106499Y929150I1195J0D01*
G02X106982Y929350I483J-483D01*
G01X107399D01*
G02X108424Y928926I1J-1449D01*
G01X109099Y928250D01*
G01X11069Y675192D02*
X18982D01*
X18988Y675198D01*
G03X20200Y675700I0J1714D01*
G01X20650Y676151D01*
G02X21533Y676516I883J-886D01*
G03X21536Y676517I-842J2531D01*
G01X26438D01*
G03X31419Y678581I-2J7046D01*
G01Y678580D01*
X32919Y680080D01*
X32920D01*
X33347Y680507D01*
G03X35000Y684499I-3994J3992D01*
G01Y691379D01*
G02X36500Y695000I5121J0D01*
G01X94249Y752749D01*
Y752750D01*
G03X96100Y757219I-4468J4468D01*
G01Y836499D01*
G03X93811Y842029I-7819J2D01*
G01X93170Y842670D01*
X93169Y842669D01*
Y842671D01*
X67170Y868670D01*
X62979Y872860D01*
X62978Y872859D01*
X62736Y873102D01*
G02X60500Y878500I5398J5398D01*
G01Y1325111D01*
G02X63250Y1331750I9389J0D01*
G01X84500Y1353000D01*
G02X89328Y1355000I4828J-4828D01*
G01X94486D01*
G02X96216Y1354283I0J-2445D01*
G01X96294Y1354206D01*
G02X97000Y1352500I-1706J-1705D01*
G01Y1349190D01*
G03X98080Y1346580I3691J-1D01*
G03X100821Y1345675I2269J2268D01*
G02X101350Y1345500I91J-612D01*
G01X102350Y1344500D01*
G01Y1348154D02*
X101696Y1347500D01*
G02X99000I-1348J1348D01*
G02X98300Y1349190I1690J1690D01*
G01Y1352500D01*
X98299D01*
G03X97211Y1355129I-3712J3D01*
G01X97130Y1355208D01*
G03X94494Y1356300I-2636J-2636D01*
G01X89327D01*
G03X83581Y1353919I2J-8128D01*
G01X83580D01*
X62330Y1332669D01*
X62331D01*
G03X59200Y1325112I7558J-7558D01*
G01Y878499D01*
G03X61816Y872182I8935J0D01*
G01X62059Y871939D01*
X62060Y871940D01*
X92891Y841109D01*
G02X94800Y836500I-4609J-4609D01*
G01Y757218D01*
G02X93330Y753669I-5019J0D01*
G01X35580Y695919D01*
X35581D01*
G03X33700Y691380I4540J-4541D01*
G01Y684500D01*
G02X32427Y681427I-4346J0D01*
G01X30500Y679500D01*
G02X26437Y677817I-4063J4063D01*
G01X21535D01*
G02X20569Y678217I0J1366D01*
G03X18353Y679135I-2216J-2216D01*
G01X18347Y679129D01*
X11069D01*
G01X112440Y1358196D02*
G02X112291Y1358258I0J210D01*
G01X111702Y1358847D01*
G03X110005Y1359550I-1697J-1697D01*
G01X101193D01*
G02X98576Y1360633I-1J3700D01*
G01X98329Y1360880D01*
G03X96745Y1361536I-1584J-1584D01*
G01X22165D01*
G03X21187Y1361131I0J-1383D01*
G02X19026Y1360236I-2161J2161D01*
G01X19020Y1360230D01*
X11069D01*
G01X112999Y1361550D02*
G02X111309Y1360850I-1690J1690D01*
G01X101193D01*
G02X99496Y1361553I0J2400D01*
G03X96384Y1362842I-3112J-3112D01*
G01X93644D01*
X93638Y1362836D01*
X22133D01*
G02X20897Y1363348I0J1748D01*
G03X18905Y1364173I-1992J-1992D01*
G01X18899Y1364167D01*
X11069D01*
G01Y1379915D02*
X11075Y1379921D01*
X19953D01*
G02X21143Y1379428I0J-1683D01*
G01X21277Y1379294D01*
G03X22699Y1378705I1422J1422D01*
G01X26610D01*
G03X28392Y1379443I0J2520D01*
G01X28796Y1379847D01*
G03X29499Y1381544I-1697J1697D01*
G01Y1389500D01*
G03X29110Y1390439I-1328J0D01*
G01X28499Y1391050D01*
G01X11069Y1375978D02*
X18519D01*
X18525Y1375984D01*
G03X21099Y1377050I0J3640D01*
G02X21659Y1377367I855J-858D01*
G02X21696Y1377376I305J-1173D01*
G02X21956Y1377405I264J-1183D01*
G01X26610D01*
G03X29312Y1378523I1J3821D01*
G01X29716Y1378927D01*
G03X30799Y1381544I-2617J2616D01*
G01Y1387347D01*
G02X31154Y1388204I1212J0D01*
G01X32333Y1389383D01*
G01X34465Y1481683D02*
X34336Y1481555D01*
G03X33299Y1479050I2505J-2504D01*
G01Y1474811D01*
G02X31206Y1469757I-7148J0D01*
G01X26499Y1465050D01*
X26303Y1464855D01*
G02X23999Y1463900I-2305J2304D01*
G01X21638D01*
G03X20721Y1463520I0J-1297D01*
G02X18500Y1462600I-2221J2221D01*
G01X18494Y1462594D01*
X11069D01*
G01X30999Y1482050D02*
G02X31999Y1479636I-2414J-2414D01*
G01Y1474810D01*
G02X30286Y1470677I-5847J2D01*
G01X25580Y1465971D01*
X25384Y1465776D01*
X25383Y1465775D01*
G02X23998Y1465200I-1386J1383D01*
G01X21736D01*
G02X20630Y1465658I0J1564D01*
G03X18508Y1466537I-2122J-2122D01*
G01X18502Y1466531D01*
X11069D01*
G01X30378Y1462518D02*
G02X30977Y1461319I-1500J-1498D01*
G02X30999Y1461019I-2098J-305D01*
G01Y1458050D01*
G02X29471Y1454361I-5217J0D01*
G01X26329Y1451219D01*
X25667Y1450556D01*
X25290Y1450178D01*
G02X23536Y1449452I-1754J1755D01*
G01X22443D01*
G02X22174Y1449469I-6J2042D01*
G02X20999Y1450050I270J2024D01*
G03X19215Y1450789I-1784J-1784D01*
G01X19209Y1450783D01*
X11069D01*
G01X33915Y1462681D02*
G03X32575Y1462126I0J-1895D01*
G01X32499Y1462050D01*
G03X32299Y1461567I483J-483D01*
G01Y1458050D01*
G02X30391Y1453441I-6518J-1D01*
G01X26587Y1449637D01*
X26210Y1449259D01*
G02X23536Y1448152I-2673J2674D01*
G01X22273D01*
G03X20863Y1447568I0J-1994D01*
G02X19134Y1446852I-1729J1729D01*
G01X19128Y1446846D01*
X11069D01*
G01X32094Y1448448D02*
G03X31499Y1447012I1436J-1436D01*
G01Y1444550D01*
G02X30086Y1441136I-4828J-1D01*
G01X28951Y1440001D01*
G03X28928Y1439981I2724J-3156D01*
G03X27743Y1438118I2800J-3089D01*
G01X27742D01*
G03X27500Y1436500I5273J-1616D01*
G01Y1434946D01*
G02X25100Y1432546I-2400J0D01*
G01X22954D01*
G03X21257Y1431843I0J-2400D01*
G02X19473Y1431104I-1784J1784D01*
G01X19467Y1431098D01*
X11069D01*
G01Y1435035D02*
X18940D01*
X18946Y1435041D01*
G02X20411Y1434434I0J-2072D01*
G03X21831Y1433846I1420J1421D01*
G01X25100D01*
G03X26200Y1434946I0J1100D01*
G01Y1436500D01*
G02X26500Y1438500I6814J0D01*
G02X28055Y1440945I5228J-1608D01*
G01X29166Y1442056D01*
G03X30199Y1444550I-2494J2494D01*
G01Y1446050D01*
G03X29673Y1447320I-1796J0D01*
G01X28697Y1448296D01*
G01X32451Y1411468D02*
G03X31499Y1409170I2298J-2298D01*
G01Y1401947D01*
G02X29918Y1398130I-5398J0D01*
G01X26118Y1394330D01*
X25759Y1393970D01*
G02X23988Y1393237I-1770J1771D01*
G01X23201D01*
X23188Y1393224D01*
G03X21833Y1392547I340J-2375D01*
G01X21702Y1392416D01*
G02X20051Y1391732I-1651J1651D01*
G01X11075D01*
X11069Y1391726D01*
G01X28999Y1411550D02*
X29280Y1411269D01*
G02X30199Y1409050I-2219J-2219D01*
G01Y1401946D01*
X30198Y1401947D01*
G02X28999Y1399049I-4098J-2D01*
G01X28998D01*
X25197Y1395248D01*
X24839Y1394889D01*
G02X23988Y1394537I-851J852D01*
G01X23201D01*
X23188Y1394550D01*
X22281D01*
G02X20946Y1395103I0J1888D01*
G03X19580Y1395669I-1366J-1366D01*
G01X19574Y1395663D01*
X11069D01*
G01X33206Y1432352D02*
G03X32140Y1429778I2574J-2574D01*
G01Y1426050D01*
G02X30473Y1422023I-5694J-1D01*
G01X27248Y1418799D01*
X26753Y1418305D01*
G02X22999Y1416751I-3753J3755D01*
G01Y1416750D01*
X22693D01*
G03X20996Y1416047I0J-2400D01*
G02X19328Y1415356I-1668J1668D01*
G01X19322Y1415350D01*
X11069D01*
G01X30499Y1434550D02*
G02X30840Y1433727I-823J-823D01*
G01Y1426050D01*
G02X29553Y1422943I-4394J0D01*
G01X26329Y1419719D01*
X25834Y1419225D01*
G02X22999Y1418050I-2836J2835D01*
G01X21864D01*
G02X20387Y1418662I0J2088D01*
G03X18864Y1419293I-1523J-1523D01*
G01X18858Y1419287D01*
X11069D01*
G01X34099Y1497550D02*
X34001Y1497452D01*
G03X32799Y1494550I2902J-2902D01*
G01Y1490112D01*
G02X31667Y1487379I-3865J0D01*
G01X28932Y1484644D01*
G03X28453Y1483490I1154J-1155D01*
G01Y1483487D01*
G02X27723Y1481725I-2492J0D01*
G01X26632Y1480634D01*
X26578Y1480578D01*
G02X24099Y1479551I-2476J2470D01*
G01Y1479550D01*
X21887D01*
G03X21633Y1479520I1J-1096D01*
G03X21111Y1479228I256J-1070D01*
G01X20966Y1479083D01*
G02X19192Y1478348I-1774J1774D01*
G01X19186Y1478342D01*
X11069D01*
G01X30499Y1497550D02*
G02X31499Y1495136I-2414J-2414D01*
G01Y1490050D01*
G02X30793Y1488344I-2412J-1D01*
G01X28676Y1486228D01*
X28012Y1485564D01*
G03X27154Y1483490I2075J-2073D01*
G01Y1483489D01*
G02X26804Y1482645I-1195J1D01*
G01X25704Y1481545D01*
X25653Y1481493D01*
G02X24099Y1480850I-1553J1554D01*
G01X21982D01*
G02X21499Y1481050I0J683D01*
G01X20974Y1481575D01*
G03X19260Y1482285I-1714J-1714D01*
G01X19254Y1482279D01*
X11069D01*
G01X104935Y1440634D02*
X105108D01*
G03X106088Y1441040I0J1386D01*
G03X106507Y1442050I-1010J1011D01*
G01Y1442550D01*
G02X106750Y1443135I828J-1D01*
G01X107053Y1443439D01*
G02X107934Y1443641I880J-1816D01*
G01X108999D01*
G02X109849Y1443289I0J-1202D01*
G02X109999Y1442927I-362J-362D01*
G01Y1437049D01*
G02X109000Y1436050I-999J0D01*
G01X104044D01*
G02X100550Y1437497I0J4943D01*
G01X99911Y1438137D01*
Y1438138D01*
X53499Y1484550D01*
X53327Y1484721D01*
G02X50499Y1491550I6829J6828D01*
G01Y1510053D01*
X50500D01*
G03X48151Y1515934I-8540J-2D01*
G01X48146Y1515944D01*
X40518Y1523571D01*
X40024Y1524064D01*
G03X35228Y1526051I-4797J-4798D01*
G01X33499D01*
G03X29508Y1524398I0J-5644D01*
G01X28475Y1523365D01*
G03X26480Y1518550I4815J-4816D01*
G01Y1515550D01*
G02X25740Y1513765I-2525J1D01*
G01X25292Y1513316D01*
X25265Y1513288D01*
G02X22999Y1512350I-2265J2266D01*
G01X22262D01*
G02X21255Y1512767I0J1424D01*
G01X20985Y1513037D01*
G03X19189Y1513781I-1796J-1796D01*
G01X19183Y1513775D01*
X11069D01*
G01Y1509838D02*
X19440D01*
X19446Y1509844D01*
G03X20689Y1510359I0J1758D01*
G02X22357Y1511050I1668J-1668D01*
G01X22999D01*
G03X26194Y1512377I2J4505D01*
G01X26221Y1512405D01*
X26432Y1512616D01*
X26659Y1512842D01*
G03X27780Y1515550I-2708J2707D01*
G01Y1518549D01*
G02X29395Y1522445I5509J-1D01*
G01X30441Y1523491D01*
G02X33483Y1524751I3042J-3042D01*
G01X35227D01*
Y1524750D01*
G02X39105Y1523144I0J-5484D01*
G01X39599Y1522651D01*
X47077Y1515173D01*
X47078Y1515171D01*
G02X49199Y1510052I-5115J-5118D01*
G02Y1510050I-7245J-1D01*
G01Y1491550D01*
G03X52408Y1483803I10956J0D01*
G01X52409Y1483802D01*
X52635Y1483575D01*
X55829Y1480380D01*
X98991Y1437218D01*
X99630Y1436578D01*
G03X104045Y1434750I4414J4415D01*
G01X109000D01*
G03X111299Y1437049I0J2299D01*
G01Y1443050D01*
G03X110854Y1444124I-1519J0D01*
G01X110772Y1444206D01*
G03X108999Y1444940I-1773J-1773D01*
G01Y1444941D01*
X104999D01*
G01X30115Y1511900D02*
G02X30999Y1509766I-2134J-2134D01*
G01Y1505050D01*
G02X29920Y1502445I-3684J0D01*
G01X24728Y1497253D01*
G02X23031Y1496550I-1697J1697D01*
G01X22967D01*
G02X21270Y1497253I0J2400D01*
G03X19387Y1498033I-1883J-1883D01*
G01X19381Y1498027D01*
X11069D01*
G01X33512Y1512051D02*
G03X32299Y1509123I2928J-2928D01*
G01Y1505050D01*
G02X30838Y1501523I-4988J0D01*
G01X25648Y1496333D01*
G02X23031Y1495250I-2616J2617D01*
G01X22967D01*
G02X22916I-25J3700D01*
G01X22501D01*
G03X21049Y1494648I0J-2052D01*
G01X21000Y1494600D01*
G02X19783Y1494096I-1217J1217D01*
G01X11075D01*
X11069Y1494090D01*
G01X29499Y1630050D02*
G02X30199Y1628360I-1690J-1690D01*
G01Y1622356D01*
G02X28596Y1618486I-5473J0D01*
G01X25648Y1615538D01*
G02X23958Y1614807I-1768J1769D01*
G02X23880Y1614806I-71J2500D01*
G01X21747D01*
G02X20617Y1615274I0J1598D01*
G03X18519Y1616143I-2098J-2098D01*
G01X18513Y1616137D01*
X11069D01*
G01X28899Y1613524D02*
X29518Y1612906D01*
G02X30079Y1611550I-1356J-1355D01*
G01Y1603950D01*
G02X29499Y1602550I-1980J0D01*
G01X27779Y1600830D01*
G02X22999Y1598850I-4780J4780D01*
G01X21723D01*
G02X20655Y1599293I1J1511D01*
G01X20654D01*
G03X17994Y1600395I-2660J-2660D01*
G01X17988Y1600389D01*
X11069D01*
G01X29626Y1645002D02*
G02X30579Y1642701I-2301J-2301D01*
G01Y1638549D01*
X30578Y1638550D01*
Y1638519D01*
G02X30554Y1638044I-4721J0D01*
G02X29108Y1634997I-4999J506D01*
G01X29079Y1634969D01*
X25829Y1631719D01*
X25482Y1631373D01*
G02X23821Y1630569I-1985J1982D01*
G01X22160D01*
G02X21086Y1631014I0J1519D01*
G01X20800Y1631300D01*
G03X19373Y1631891I-1427J-1427D01*
G01X19367Y1631885D01*
X11069D01*
G01X33026Y1645051D02*
G03X31879Y1642282I2769J-2769D01*
G01Y1638550D01*
G02X30026Y1634078I-6324J0D01*
G01X29999Y1634050D01*
X26748Y1630799D01*
X26401Y1630453D01*
G02X23972Y1629278I-2903J2903D01*
G01X22200D01*
G03X22174Y1629277I77J-2346D01*
G01X22092Y1629273D01*
G03X20539Y1628590I102J-2339D01*
G02X19004Y1627954I-1535J1535D01*
G01X18998Y1627948D01*
X11069D01*
G01X30520Y1572049D02*
G02X29669Y1569455I-7152J910D01*
G02X27499Y1567050I-6301J3504D01*
G02X27129Y1566818I-2498J3573D01*
G02X24999Y1566262I-2130J3804D01*
G01X21655D01*
G03X21477Y1566251I6J-1550D01*
G03X20666Y1565915I0J-1147D01*
G01X20559Y1565808D01*
G02X18517Y1564962I-2042J2042D01*
G01X18511Y1564956D01*
X11069D01*
G01X32299Y1613524D02*
X32111Y1613336D01*
G03X31379Y1611568I1769J-1768D01*
G01Y1603949D01*
G02X30419Y1601630I-3280J0D01*
G01X28699Y1599910D01*
G02X24830Y1597760I-5699J5700D01*
G02X22999Y1597550I-1828J7851D01*
G01X21499D01*
G03X20944Y1597320I0J-785D01*
G02X18863Y1596458I-2081J2081D01*
G01X18857Y1596452D01*
X11069D01*
G01X32663Y1628181D02*
X32183Y1627701D01*
G03X31698Y1626994I1650J-1652D01*
G03X31499Y1626050I2136J-943D01*
G01Y1622550D01*
G02X29378Y1617428I-7243J-1D01*
G01X29315Y1617366D01*
X26999Y1615050D01*
Y1615049D01*
X26568Y1614618D01*
G02X23997Y1613507I-2688J2689D01*
G02X23879Y1613506I-91J3800D01*
G01X21710D01*
G03X20625Y1613056I1J-1535D01*
G01X20624D01*
G02X18572Y1612206I-2052J2052D01*
G01X18566Y1612200D01*
X11069D01*
G01X27123Y1572205D02*
G02X28012Y1569771I-1592J-1961D01*
G02X26856Y1568094I-2481J473D01*
G02X26573Y1567937I-1859J3017D01*
G02X24999Y1567568I-1575J3175D01*
G01X21322D01*
G02X20266Y1568006I1J1494D01*
G01X20265D01*
G03X18109Y1568899I-2156J-2156D01*
G01X18103Y1568893D01*
X11069D01*
G01X31999Y1661127D02*
G03X30999Y1658713I2414J-2414D01*
G01Y1652405D01*
G02X29431Y1648618I-5357J0D01*
G01X29181Y1648368D01*
Y1648367D01*
X28620Y1647807D01*
X28500Y1647687D01*
Y1647686D01*
X27101Y1646287D01*
G02X23999Y1645002I-3102J3102D01*
G01X21710D01*
G03X20626Y1644553I0J-1533D01*
G02X18572Y1643702I-2054J2054D01*
G01X18566Y1643696D01*
X11069D01*
G01X28600Y1661039D02*
G02X29699Y1658386I-2653J-2653D01*
G01Y1652406D01*
G02X28511Y1649538I-4056J0D01*
G01X27200Y1648227D01*
Y1648225D01*
X27011Y1648037D01*
X26181Y1647207D01*
G02X25465Y1646673I-2184J2181D01*
G01Y1646674D01*
G02X23999Y1646302I-1469J2714D01*
G01X21641D01*
G02X20740Y1646675I0J1274D01*
G03X18413Y1647639I-2327J-2327D01*
G01X18407Y1647633D01*
X11069D01*
G01X32494Y1669706D02*
X31703Y1668916D01*
G03X31200Y1667702I1214J-1214D01*
G01Y1667700D01*
G02X30819Y1666780I-1301J0D01*
G01X26523Y1662484D01*
X26410Y1662369D01*
G02X22500Y1660751I-3907J3907D01*
G01Y1660750D01*
X22188D01*
G03X21353Y1660404I0J-1181D01*
G02X19050Y1659450I-2303J2303D01*
G01X19044Y1659444D01*
X11069D01*
G01X29100Y1669500D02*
G02X29549Y1667350I-479J-1222D01*
G01X25599Y1663400D01*
X25487Y1663285D01*
G02X25228Y1663048I-2979J2996D01*
G02X22500Y1662050I-2727J3227D01*
G01X21766D01*
G02X20590Y1662537I0J1663D01*
G03X18538Y1663387I-2052J-2052D01*
G01X18532Y1663381D01*
X11069D01*
G01X86899Y130567D02*
G03X86099Y129767I0J-800D01*
G03X87016Y128850I917J0D01*
G01X92014D01*
G03X98579Y131570I0J9283D01*
G03X99998Y134996I-3426J3426D01*
G01X99999Y134995D01*
Y177250D01*
G03X92007Y196542I-27284J-1D01*
G01X65456Y223093D01*
G02X63699Y227334I4242J4242D01*
G01Y352756D01*
G03X62967Y354524I-2500J0D01*
G01X39131Y378360D01*
G03X38160Y378684I-799J-778D01*
G02X37190Y379007I-172J1102D01*
G01X36394Y379803D01*
G02X36071Y380773I778J798D01*
G03X35747Y381744I-1102J172D01*
G01X33132Y384359D01*
G03X31364Y385091I-1768J-1768D01*
G01X28399D01*
G03X26926Y384481I0J-2083D01*
G01X26299Y383854D01*
G01X86599Y126750D02*
X86671Y126822D01*
G02X87835Y127478I1757J-1757D01*
G02X88146Y127534I595J-2413D01*
G02X88423Y127550I281J-2456D01*
G01X92015D01*
G03X99499Y130650I0J10584D01*
G03X101299Y134996I-4346J4346D01*
G01Y177250D01*
G03X92927Y197462I-28584J0D01*
G01X66376Y224013D01*
G02X64999Y227335I3322J3323D01*
G01Y352757D01*
G03X63886Y355444I-3800J0D01*
G01X34052Y385278D01*
G03X31365Y386391I-2687J-2687D01*
G01X28499D01*
G02X26857Y387071I0J2322D01*
G01X26299Y387629D01*
G01Y399601D02*
G02X27536Y400838I1237J0D01*
G01X31136D01*
G02X31605Y400644I0J-664D01*
G01X69342Y362907D01*
G02X71099Y358665I-4242J-4242D01*
G01Y294350D01*
G03X72470Y291040I4681J0D01*
G01X125479Y238031D01*
X126008Y237501D01*
G03X130599Y235600I4590J4591D01*
G01X816263D01*
G03X821425Y237737I1J7300D01*
G01X836553Y252863D01*
G02X839875Y254240I3323J-3322D01*
G01X859116D01*
G02X860299Y253750I0J-1673D01*
G01X871899Y242150D01*
G03X874555Y241050I2656J2656D01*
G01X876199D01*
G02X876593Y241015I-1J-2250D01*
G02X877571Y240610I0J-1383D01*
G01X878078Y240103D01*
G01X26299Y403376D02*
X27162Y402513D01*
G03X28067Y402138I905J905D01*
G01X31141D01*
G02X31789Y402027I0J-1947D01*
G02X32524Y401564I-654J-1853D01*
G01X33944Y400145D01*
X70262Y363827D01*
G02X72399Y358665I-5163J-5161D01*
G01Y294223D01*
G03X73299Y292050I3073J0D01*
G01X126249Y239100D01*
X126928Y238420D01*
G03X130599Y236900I3670J3671D01*
G01X816263D01*
G03X820505Y238657I0J5999D01*
G01X835633Y253783D01*
G02X839875Y255540I4242J-4242D01*
G01X859118D01*
G02X861218Y254670I0J-2970D01*
G01X873018Y242870D01*
G03X874273Y242350I1255J1255D01*
G01X875999D01*
G03X876939Y242740I-1J1330D01*
G01X878078Y243878D01*
G01X149999Y243504D02*
G02X148420Y242850I-1579J1579D01*
G01X140335D01*
G02X139249Y243300I0J1536D01*
G01X132649Y249900D01*
G02X132368Y250212I2773J2780D01*
G02X131499Y252676I3057J2463D01*
G01Y256550D01*
G03X130386Y259237I-3800J0D01*
G01X130016Y259607D01*
X127961Y261667D01*
X127956D01*
X81086Y308537D01*
G02X79799Y311644I3107J3107D01*
G01Y375915D01*
G03X78686Y378602I-3800J0D01*
G01X33143Y424145D01*
X33144Y424146D01*
X32065Y425224D01*
G03X30530Y425859I-1534J-1535D01*
G01X28499D01*
G02X26598Y426647I1J2689D01*
G01X26524Y426720D01*
G01X149999Y239729D02*
G03X149489Y240960I-1741J0D01*
G01X149199Y241250D01*
G03X148475Y241550I-724J-724D01*
G01X140334D01*
G02X138329Y242380I0J2837D01*
G01X131729Y248980D01*
G02X131356Y249396I3699J3692D01*
G02X130199Y252675I4069J3280D01*
G01Y256550D01*
G03X129468Y258315I-2496J0D01*
G01X129289Y258494D01*
X127421Y260367D01*
X127415D01*
X119554Y268229D01*
X80166Y307617D01*
G02X78499Y311643I4028J4026D01*
G01Y375914D01*
G03X77767Y377682I-2500J0D01*
G01X32224Y423225D01*
Y423224D01*
X31304Y424145D01*
Y424146D01*
X31146Y424304D01*
G03X30531Y424559I-615J-615D01*
G01X27099D01*
G03X26399Y423859I0J-700D01*
G01Y423322D01*
G01X26492Y439350D02*
G02X29099Y440212I2607J-3511D01*
G01X162266D01*
G03X164665Y441065I0J3800D01*
G01Y441064D01*
G03X164671Y441069I-2430J2922D01*
G01X164675Y441072D01*
X179292Y453194D01*
X180630Y454302D01*
X181279Y454693D01*
X181877Y454932D01*
X181881D01*
X834463Y659784D01*
G02X835871Y660000I1408J-4484D01*
G01X849603D01*
G02X852925Y658623I-1J-4699D01*
G01X863698Y647850D01*
G03X866636Y646633I2938J2938D01*
G01X877079D01*
G02X877859Y646310I0J-1103D01*
G01X878596Y645573D01*
G01X26599Y442749D02*
G03X29126Y441512I2601J2113D01*
G01X162266D01*
G03X163845Y442073I1J2500D01*
G01X179869Y455363D01*
X180699Y455862D01*
X181439Y456157D01*
X181843Y456317D01*
X181949D01*
X834074Y661025D01*
G02X835871Y661300I1796J-5725D01*
G01X849603D01*
G02X853845Y659543I0J-5999D01*
G01X864618Y648770D01*
G03X866639Y647933I2021J2021D01*
G01X876521D01*
G03X877648Y648400I0J1594D01*
G01X878596Y649348D01*
G01X26899Y454850D02*
G02X28008Y455959I1109J0D01*
G01X34796D01*
G03X38897Y457658I0J5800D01*
G01X44621Y463382D01*
G02X47803Y464700I3182J-3182D01*
G01X172226D01*
G03X179843Y467855I-1J10774D01*
G01X179942Y467954D01*
X179943D01*
X775339Y1063350D01*
G02X781490Y1065899I6152J-6150D01*
G01X867280D01*
G02X868593Y1065355I-1J-1858D01*
G01X868710Y1065239D01*
G02X869138Y1064206I-1031J-1032D01*
G01Y1055550D01*
G03X870182Y1053027I3567J-1D01*
G01X870379Y1052830D01*
G03X872749Y1051850I2367J2369D01*
G01X875000D01*
G03X876837Y1052183I0J5235D01*
G02X878232Y1051216I362J-967D01*
G01X878233Y1051095D01*
G01X26799Y458497D02*
G03X28037Y457259I1238J0D01*
G01X34795D01*
G03X37977Y458577I0J4500D01*
G01X43701Y464301D01*
G02X47802Y466000I4101J-4101D01*
G01X172225D01*
G03X178924Y468775I0J9474D01*
G01X179403Y469254D01*
X179404D01*
X774419Y1064270D01*
G02X781489Y1067199I7071J-7071D01*
G01X867281D01*
G02X869510Y1066277I-1J-3158D01*
G01X869627Y1066161D01*
G02X870438Y1064205I-1948J-1954D01*
G01Y1055550D01*
G03X871102Y1053947I2267J0D01*
G01X871299Y1053750D01*
G03X872748Y1053150I1449J1449D01*
G01X874999D01*
G03X877781Y1054303I-1J3935D01*
G01X877964Y1054485D01*
G01X866914Y1861840D02*
Y1862634D01*
G03X865999Y1863549I-915J0D01*
G01X863498D01*
G03X858815Y1861610I0J-6625D01*
G03X857200Y1859550I7715J-7711D01*
G01X856546Y1858472D01*
X854323Y1854804D01*
X816662Y1792440D01*
X813915Y1787895D01*
X654096Y1523249D01*
X489900Y1251355D01*
X443578Y1174650D01*
X399315Y1101355D01*
X339087Y1001622D01*
X293567Y926245D01*
X292455Y924404D01*
X196628Y761569D01*
X173941Y728157D01*
X163141Y710272D01*
X160430Y705784D01*
X158893Y703238D01*
X127954Y652007D01*
X125902Y648609D01*
X84499Y580050D01*
X40409Y520331D01*
X40398Y520330D01*
X40108Y520045D01*
X38785Y518722D01*
G02X36499Y517775I-2286J2286D01*
G01Y521550D02*
Y521451D01*
G03X37136Y519913I2175J0D01*
G03X38136I500J500D01*
G01X39196Y520973D01*
X39487Y521259D01*
Y521271D01*
X83417Y580774D01*
X125168Y649909D01*
X126831Y652663D01*
X126840Y652679D01*
X157779Y703910D01*
X159317Y706457D01*
X161491Y710056D01*
X172846Y728859D01*
X195529Y762265D01*
X291338Y925070D01*
X398202Y1102027D01*
X488787Y1252027D01*
X652983Y1523921D01*
X812802Y1788567D01*
X815549Y1793112D01*
X853210Y1855477D01*
X855434Y1859146D01*
X856088Y1860224D01*
X856092Y1860231D01*
G02X857895Y1862530I10416J-6312D01*
G02X863498Y1864850I5603J-5606D01*
G01X865067D01*
G03X866914Y1865615I0J2612D01*
G01X26399Y501966D02*
G02X27636Y503203I1237J0D01*
G01X37765D01*
G03X44951Y506002I-62J10783D01*
G01Y506003D01*
X65198Y526249D01*
X65252Y526306D01*
X66621Y527849D01*
X67656Y529107D01*
X67662Y529115D01*
X405841Y946376D01*
X569817Y1148697D01*
X817499Y1454298D01*
X817598Y1454420D01*
X818213Y1455179D01*
X818212Y1455180D01*
X818955Y1456096D01*
X818949Y1456100D01*
X833149Y1470300D01*
G02X835443Y1471250I2294J-2294D01*
G01X853607D01*
G02X857349Y1469700I0J-5292D01*
G01X868486Y1458563D01*
G03X871173Y1457450I2687J2687D01*
G01X877054D01*
G02X878054Y1456450I0J-1000D01*
G01X26399Y505741D02*
X26674Y505466D01*
G03X28999Y504503I2325J2325D01*
G01X37761D01*
G03X44054Y506945I-59J9482D01*
G01X64279Y527169D01*
X64293Y527185D01*
X65632Y528694D01*
X66651Y529934D01*
X68290Y531957D01*
X404830Y947194D01*
X568807Y1149516D01*
X817202Y1455998D01*
X818030Y1457020D01*
X832229Y1471219D01*
G02X835443Y1472550I3213J-3213D01*
G01X853299D01*
G02X858487Y1470401I0J-7337D01*
G01X869406Y1459482D01*
G03X871174Y1458750I1768J1768D01*
G01X876612D01*
G03X877853Y1459991I0J1241D01*
G01X27499Y620203D02*
G02X30341Y621380I2842J-2842D01*
G01X47689D01*
G03X64999Y628550I0J24480D01*
G03X67499Y634586I-6036J6036D01*
G01Y667156D01*
G02X69518Y672030I6893J0D01*
G01X139768Y742280D01*
Y742281D01*
G03X140867Y744932I-2652J2653D01*
G01Y766866D01*
G02X142336Y770412I5015J0D01*
G01X183037Y811113D01*
G03X184999Y815850I-4739J4738D01*
G01Y1173709D01*
G03X184108Y1175860I-3042J0D01*
G01X162958Y1197010D01*
G02X161399Y1200774I3764J3764D01*
G01Y1374674D01*
G03X160498Y1376849I-3076J0D01*
G01X131698Y1405649D01*
G02X130049Y1409630I3981J3981D01*
G01Y1447624D01*
G03X128152Y1452204I-6477J0D01*
G01X115702Y1464654D01*
G02X113499Y1469973I5319J5319D01*
G01Y1647666D01*
G02X116599Y1655150I10584J0D01*
G01X145198Y1683749D01*
G03X148799Y1692443I-8693J8693D01*
G01Y1799801D01*
G03X146287Y1805651I-7903J71D01*
G02X134766Y1816775I310791J333411D01*
G01X134765Y1816774D01*
G02X132900Y1821277I4503J4503D01*
G01Y1860421D01*
G02X133421Y1861679I1779J0D01*
G01X133564Y1861822D01*
G02X135200Y1862500I1636J-1635D01*
G01X136300D01*
G02X137488Y1862008I0J-1680D01*
G01X137999Y1861497D01*
G01X27499Y623857D02*
G03X30341Y622680I2842J2842D01*
G01X47689D01*
G03X64079Y629470I-1J23179D01*
G03X66198Y634586I-5116J5116D01*
G01X66199Y634585D01*
Y667157D01*
G02X68598Y672949I8193J-1D01*
G01X138849Y743200D01*
G03X139567Y744933I-1733J1733D01*
G01Y766750D01*
G02X141499Y771414I6596J0D01*
G01X182117Y812032D01*
G03X183699Y815851I-3819J3819D01*
G01Y1173708D01*
G03X183188Y1174941I-1742J0D01*
G01X162039Y1196090D01*
G02X160099Y1200774I4683J4683D01*
G01Y1374673D01*
G03X159578Y1375930I-1776J0D01*
G01X130778Y1404730D01*
G02X128749Y1409629I4901J4900D01*
G01Y1447625D01*
X128748Y1447624D01*
G03X127233Y1451284I-5177J1D01*
G01X114783Y1463734D01*
G02X112199Y1469973I6238J6238D01*
G01Y1647667D01*
G02X115679Y1656069I11884J-1D01*
G01X144279Y1684669D01*
G03X147499Y1692442I-7774J7774D01*
G01Y1799800D01*
G03X145400Y1804700I-6603J71D01*
G02X133846Y1815855I311665J334374D01*
G02X131600Y1821278I5422J5422D01*
G01Y1860420D01*
G02X132502Y1862598I3079J1D01*
G01X132501Y1862599D01*
X132644Y1862742D01*
G02X135199Y1863800I2555J-2556D01*
G01X135800D01*
G03X137247Y1864400I-1J2047D01*
G01X137999Y1865151D01*
G01X26568Y635950D02*
G02X29410Y637127I2842J-2842D01*
G01X51649D01*
G03X57499Y639550I0J8273D01*
G03X59499Y644378I-4828J4828D01*
G01Y670641D01*
G02X61669Y675880I7409J0D01*
G01X131419Y745630D01*
X132380Y746590D01*
G03X133314Y748849I-2260J2257D01*
G01Y770461D01*
G02X134302Y772846I3373J0D01*
G01X175453Y813997D01*
G03X177299Y818454I-4459J4458D01*
G01Y1170469D01*
G03X176074Y1173426I-4182J0D01*
G01X155424Y1194076D01*
G02X153999Y1197516I3440J3440D01*
G01Y1371699D01*
G03X153164Y1373715I-2851J0D01*
G01X123964Y1402915D01*
G02X122649Y1406090I3175J3175D01*
G01Y1443518D01*
G03X120018Y1449870I-8983J0D01*
G01X107168Y1462720D01*
G02X105299Y1467232I4512J4512D01*
G01Y1684107D01*
G03X104144Y1686895I-3943J0D01*
G01X99944Y1691095D01*
G02X98549Y1694463I3368J3368D01*
G01Y1742717D01*
G03X97436Y1745404I-3800J0D01*
G01X93396Y1749444D01*
G03X89999Y1750850I-3396J-3398D01*
G01X87699D01*
G02X87258Y1750892I-1J2325D01*
G02X86056Y1751530I439J2279D01*
G01X85341Y1752245D01*
G01X85194Y1748848D02*
G02X86889Y1749550I1695J-1695D01*
G01X89999D01*
G02X92476Y1748524I0J-3503D01*
G01X96517Y1744483D01*
G02X97249Y1742715I-1768J-1768D01*
G01Y1737629D01*
G02X96792Y1736714I-1115J-15D01*
G03X96334Y1735799I657J-901D01*
G01Y1734674D01*
G03X96792Y1733759I1115J-14D01*
G02X97249Y1732844I-658J-900D01*
G01Y1731719D01*
G02X96792Y1730804I-1115J-15D01*
G03X96334Y1729889I657J-901D01*
G01Y1728764D01*
G03X96792Y1727849I1115J-14D01*
G02X97249Y1726934I-658J-900D01*
G01Y1725809D01*
G02X96792Y1724894I-1115J-15D01*
G03X96334Y1723979I657J-901D01*
G01Y1722854D01*
G03X96792Y1721939I1115J-14D01*
G02X97249Y1721024I-658J-900D01*
G01Y1719899D01*
G02X96792Y1718984I-1115J-15D01*
G03X96334Y1718069I657J-901D01*
G01Y1716944D01*
G03X96792Y1716029I1115J-14D01*
G02X97249Y1715114I-658J-900D01*
G01Y1713989D01*
G02X96792Y1713074I-1115J-15D01*
G03X96334Y1712159I657J-901D01*
G01Y1711034D01*
G03X96792Y1710119I1115J-14D01*
G02X97249Y1709204I-658J-900D01*
G01Y1694463D01*
G03X99025Y1690175I6063J-1D01*
G01X103224Y1685976D01*
G02X103999Y1684106I-1868J-1870D01*
G01Y1579633D01*
G02X103542Y1578718I-1115J-15D01*
G03X103084Y1577803I657J-901D01*
G01Y1576678D01*
G03X103542Y1575763I1115J-14D01*
G02X103999Y1574848I-658J-900D01*
G01Y1573723D01*
G02X103542Y1572808I-1115J-15D01*
G03X103084Y1571893I657J-901D01*
G01Y1570768D01*
G03X103542Y1569853I1115J-14D01*
G02X103999Y1568938I-658J-900D01*
G01Y1467231D01*
G03X106248Y1461801I7681J1D01*
G01X119099Y1448950D01*
G02X121349Y1443518I-5433J-5432D01*
G01Y1406090D01*
G03X123045Y1401995I5790J-1D01*
G01X152245Y1372795D01*
G02X152698Y1371699I-1098J-1095D01*
G01X152699Y1371700D01*
Y1197515D01*
G03X154504Y1193157I6165J1D01*
G01X175154Y1172507D01*
G02X175999Y1170468I-2037J-2039D01*
G01Y818455D01*
G02X174533Y814916I-5005J0D01*
G01X133382Y773765D01*
G03X132014Y770462I3305J-3304D01*
G01Y748849D01*
G02X131460Y747510I-1893J-1D01*
G01X130499Y746550D01*
X60749Y676800D01*
X60750Y676799D01*
G03X58199Y670640I6158J-6158D01*
G01Y644379D01*
G02X56579Y640470I-5527J1D01*
G02X51650Y638427I-4931J4929D01*
G01X29410D01*
G02X26568Y639604I0J4019D01*
G01X142999Y1456373D02*
X142597Y1456775D01*
G03X141450Y1457250I-1147J-1147D01*
G01X140559D01*
G03X139874Y1457156I2J-2561D01*
G03X138749Y1456499I686J-2467D01*
G01X138150Y1455900D01*
X138149D01*
G03X137449Y1454210I1690J-1690D01*
G01Y1451939D01*
X137450Y1451938D01*
Y1446162D01*
X137449Y1446161D01*
Y1413100D01*
G03X139382Y1408433I6600J0D01*
G01X167231Y1380584D01*
G02X168799Y1376798I-3785J-3785D01*
G01Y1203961D01*
G03X170442Y1199994I5610J0D01*
G01X190892Y1179544D01*
G02X192399Y1175906I-3638J-3638D01*
G01Y812663D01*
G02X190521Y808129I-6412J0D01*
G01X150670Y768278D01*
X150470Y768079D01*
G03X148851Y764169I3910J-3909D01*
G01Y732209D01*
G02X147032Y727817I-6213J1D01*
G01X93031Y673816D01*
G02X90457Y672750I-2575J2576D01*
G01X83915D01*
G03X82418Y672130I0J-2117D01*
G01X79299Y669010D01*
G03X78768Y667799I1278J-1282D01*
G01Y665608D01*
G03X78999Y665050I789J0D01*
G03X80206Y664550I1207J1207D01*
G01X80499D01*
G01X26737Y651957D02*
G02X29376Y653050I2639J-2639D01*
G01X46585D01*
G03X48999Y654050I0J3414D01*
G03X50999Y658878I-4828J4828D01*
G01Y678812D01*
G02X53119Y683930I7238J0D01*
G01X115419Y746230D01*
G03X117499Y751253I-5025J5023D01*
G01Y1030000D01*
G03X114360Y1037578I-10717J0D01*
G01X96607Y1055331D01*
G02X95079Y1059020I3689J3689D01*
G01Y1342443D01*
G03X93999Y1345050I-3687J0D01*
G03X92792Y1345550I-1207J-1207D01*
G01X89509D01*
G02X86890Y1346635I0J3704D01*
G01X26999Y656550D02*
Y655757D01*
G03X27499Y654550I1707J0D01*
G03X27982Y654350I483J483D01*
G01X46584D01*
G03X48079Y654970I0J2113D01*
G03X49699Y658879I-3907J3910D01*
G01Y678813D01*
G02X52200Y684849I8538J-2D01*
G01X52199Y684850D01*
X114499Y747150D01*
G03X116199Y751254I-4104J4104D01*
G01Y1029999D01*
G03X113440Y1036658I-9416J0D01*
G01X95687Y1054411D01*
G02X93779Y1059021I4610J4608D01*
G01Y1316719D01*
G03X93322Y1317634I-1115J15D01*
G02X92864Y1318549I657J901D01*
G01Y1319674D01*
G02X93321Y1320589I1115J15D01*
G03X93779Y1321504I-657J901D01*
G01Y1322629D01*
G03X93322Y1323544I-1115J15D01*
G02X92864Y1324459I657J901D01*
G01Y1325584D01*
G02X93321Y1326499I1115J15D01*
G03X93779Y1327414I-657J901D01*
G01Y1342442D01*
G03X93079Y1344130I-2386J0D01*
G03X92791Y1344250I-288J-286D01*
G01X90246D01*
G03X86890Y1342860I0J-4746D01*
G01X27687Y667447D02*
Y667738D01*
G02X28999Y669050I1312J0D01*
G01X34999D01*
G03X39499Y673550I0J4500D01*
G01Y687169D01*
G02X41592Y694354I13380J0D01*
G02X43418Y696630I11287J-7185D01*
G01X99618Y752830D01*
G03X102449Y759665I-6834J6834D01*
G01Y926132D01*
G03X100818Y930070I-5568J1D01*
G01X92169Y938719D01*
G03X89262Y939923I-2906J-2906D01*
G01X87221D01*
G02X85999Y940429I0J1728D01*
G01X27687Y671101D02*
G03X29500Y670350I1813J1813D01*
G01X34999D01*
G03X38199Y673550I0J3200D01*
G01Y687170D01*
G02X40496Y695052I14680J-2D01*
G02X42499Y697549I12384J-7882D01*
G01X42498D01*
X98699Y753750D01*
G03X101149Y759665I-5915J5915D01*
G01Y804662D01*
G03X100692Y805577I-1115J15D01*
G02X100234Y806492I657J901D01*
G01Y807617D01*
G02X100692Y808532I1115J14D01*
G03X101149Y809447I-658J900D01*
G01Y902419D01*
G03X100692Y903334I-1115J15D01*
G02X100234Y904249I657J901D01*
G01Y905374D01*
G02X100692Y906289I1115J14D01*
G03X101149Y907204I-658J900D01*
G01Y908329D01*
G03X100692Y909244I-1115J15D01*
G02X100234Y910159I657J901D01*
G01Y911284D01*
G02X100692Y912199I1115J14D01*
G03X101149Y913114I-658J900D01*
G01Y914239D01*
G03X100692Y915154I-1115J15D01*
G02X100234Y916069I657J901D01*
G01Y917194D01*
G02X100692Y918109I1115J14D01*
G03X101149Y919024I-658J900D01*
G01Y926132D01*
G03X99899Y929150I-4268J0D01*
G01X91249Y937800D01*
G03X89262Y938623I-1987J-1987D01*
G01X87058D01*
G03X86399Y938350I0J-932D01*
G03Y937050I650J-650D01*
G01X76999Y664550D02*
G03X77471Y665690I-1140J1140D01*
G01Y667851D01*
G02X78379Y669930I3108J-120D01*
G01X78399Y669950D01*
X81498Y673050D01*
G02X83915Y674050I2416J-2418D01*
G01X90456D01*
G03X92112Y674736I0J2342D01*
G01X129261Y711885D01*
G03X129585Y712856I-778J799D01*
G02X129908Y713826I1102J172D01*
G01X130704Y714622D01*
G02X131674Y714945I798J-778D01*
G03X132645Y715269I172J1102D01*
G01X146112Y728736D01*
G03X147551Y732210I-3474J3474D01*
G01Y764170D01*
G02X149551Y768997I6827J-1D01*
G01Y768998D01*
X189601Y809048D01*
Y809049D01*
G03X191099Y812662I-3613J3615D01*
G01Y1175905D01*
G03X189972Y1178625I-3845J0D01*
G01X169523Y1199074D01*
G02X167499Y1203961I4886J4886D01*
G01Y1376798D01*
G03X166312Y1379664I-4053J0D01*
G01X138463Y1407513D01*
G02X136149Y1413100I5586J5586D01*
G01Y1446700D01*
X136150Y1446701D01*
Y1451399D01*
X136149Y1451400D01*
Y1454210D01*
G02X137230Y1456820I3690J0D01*
G01X137829Y1457419D01*
G02X140560Y1458550I2730J-2730D01*
G01X141450D01*
G03X142900Y1460000I0J1450D01*
G01X97229Y1373337D02*
G02X99235Y1374168I2006J-2006D01*
G01X100984D01*
G03X104200Y1375500I0J4548D01*
G03X104922Y1377243I-1743J1743D01*
G01Y1379044D01*
G03X103999Y1381050I-3173J-244D01*
G03X100378Y1382550I-3621J-3621D01*
G01X95999D01*
G03X92585Y1381136I0J-4828D01*
G01X83499Y1372050D01*
G02X80279Y1370716I-3221J3221D01*
G01X28499D01*
G02X25660Y1371892I0J4015D01*
G01X25507Y1372045D01*
G01X97000Y1377600D02*
Y1377290D01*
G03X97700Y1375600I2390J0D01*
G03X98019Y1375468I319J319D01*
G01X100985D01*
G03X103280Y1376420I-2J3247D01*
G03X103622Y1377244I-822J824D01*
G01Y1378944D01*
X103623D01*
G03X103079Y1380130I-1875J-142D01*
G03X100377Y1381250I-2702J-2700D01*
G01X95998D01*
G03X93505Y1380216I2J-3527D01*
G01X84419Y1371130D01*
G02X80278Y1369416I-4139J4142D01*
G01X72256D01*
G03X71341Y1368958I-14J-1115D01*
G02X70426Y1368501I-900J658D01*
G01X69301D01*
G02X68386Y1368958I-15J1115D01*
G03X67471Y1369416I-901J-657D01*
G01X54526D01*
G03X53611Y1368958I-14J-1115D01*
G02X52696Y1368501I-900J658D01*
G01X51571D01*
G02X50656Y1368958I-15J1115D01*
G03X49741Y1369416I-901J-657D01*
G01X48616D01*
G03X47701Y1368958I-14J-1115D01*
G02X46786Y1368501I-900J658D01*
G01X45661D01*
G02X44746Y1368958I-15J1115D01*
G03X43831Y1369416I-901J-657D01*
G01X42706D01*
G03X41791Y1368958I-14J-1115D01*
G02X40876Y1368501I-900J658D01*
G01X39751D01*
G02X38836Y1368958I-15J1115D01*
G03X37921Y1369416I-901J-657D01*
G01X36796D01*
G03X35881Y1368958I-14J-1115D01*
G02X34966Y1368501I-900J658D01*
G01X33841D01*
G02X32926Y1368958I-15J1115D01*
G03X32011Y1369416I-901J-657D01*
G01X27897D01*
G03X25558Y1368447I0J-3308D01*
G01X117390Y1426201D02*
X116778Y1426813D01*
G03X114999Y1427550I-1779J-1779D01*
G01X106369D01*
G02X100456Y1430052I130J8545D01*
G01X89004Y1441504D01*
X49809Y1480700D01*
X49810Y1480701D01*
X48479Y1482031D01*
X48209Y1482302D01*
G02X45988Y1485501I7747J7749D01*
G02X45002Y1489792I9969J4549D01*
G02X44999Y1490050I10955J256D01*
G01Y1508176D01*
G03X42839Y1513391I-7375J0D01*
G01X39089Y1517141D01*
X38414Y1517815D01*
G03X35499Y1519023I-2915J-2913D01*
G01X34499D01*
G03X32241Y1518087I1J-3194D01*
G01X31999Y1517846D01*
G01X117390Y1429976D02*
G02X114672Y1428850I-2718J2718D01*
G01X106499D01*
X106498Y1428849D01*
G02X101376Y1430972I2J7245D01*
G01X51648Y1480700D01*
X51649Y1480701D01*
X49400Y1482950D01*
X49130Y1483221D01*
X49126Y1483225D01*
G02X47173Y1486038I6830J6827D01*
G01X47172Y1486041D01*
G02X46302Y1489823I8784J4012D01*
G01X46301Y1489847D01*
G02X46299Y1490051I8568J186D01*
G01Y1508176D01*
G03X43759Y1514311I-8675J2D01*
G01X40008Y1518061D01*
X39334Y1518735D01*
G03X35499Y1520323I-3834J-3834D01*
G01X34499D01*
G02X32241Y1521259I1J3194D01*
G01X31999Y1521500D01*
G54D19*
X997607Y1602322D03*
M02*
